FILE_TYPE = MACRO_DRAWING;
SET COLOR_WIRE YELLOW;
SET COLOR_PROP ORANGE;
SET COLOR_DOT WHITE;
SET COLOR_ARC YELLOW;
SET COLOR_BODY GREEN;
SET COLOR_NOTE PURPLE;
SET PROP_DISPLAY VALUE;
SET PAGE_NUMBER P161;
FORCEADD UNIVERSAL_POWER..1
(2550 800);
FORCEPROP 3 LASTPIN (2550 750) SIG_NAME P3V3_AUX\g
J 0
(2560 760);
DISPLAY 0.659574 (2560 760);
PAINT MONO (2560 760);
DISPLAY INVISIBLE (2560 760);
FORCEPROP 1 LAST HDL_POWER P3V3_AUX
J 1
(2550 850);
DISPLAY 0.872340 (2550 850);
PAINT GREEN (2550 850);
FORCEPROP 1 LAST PATH I100
J 0
(2600 825);
DISPLAY 0.872340 (2600 825);
PAINT AQUA (2600 825);
DISPLAY INVISIBLE (2600 825);
FORCEPROP 2 LAST CDS_LIB logical_power
J 0
(2550 800);
DISPLAY INVISIBLE (2550 800);
FORCEADD Q_RES..2
(3900 125);
FORCEPROP 1 LAST PART_NUMBER CS21002FB06
J 0
(3940 -50);
DISPLAY 0.638298 (3940 -50);
DISPLAY INVISIBLE (3940 -50);
FORCEPROP 1 LAST TOLERANCE 1%
J 0
(3945 150);
DISPLAY 0.638298 (3945 150);
FORCEPROP 1 LAST WATTAGE 1/16W
J 0
(3940 100);
DISPLAY 0.638298 (3940 100);
FORCEPROP 1 LAST VALUE 1K
J 0
(3945 200);
DISPLAY 0.638298 (3945 200);
FORCEPROP 1 LAST MATERIAL EMPTY
J 0
(3940 50);
DISPLAY 0.638298 (3940 50);
PAINT RED (3940 50);
FORCEPROP 1 LAST PACK_TYPE 0402LF
J 0
(3940 0);
DISPLAY 0.638298 (3940 0);
FORCEPROP 1 LAST $LOCATION R4188
J 0
(3945 250);
DISPLAY 0.638298 (3945 250);
FORCEPROP 1 LASTPIN (3900 225) $PN 1
J 0
(3905 187);
DISPLAY 0.787234 (3905 187);
PAINT MONO (3905 187);
FORCEPROP 1 LASTPIN (3900 25) $PN 2
J 0
(3905 35);
DISPLAY 0.787234 (3905 35);
PAINT MONO (3905 35);
FORCEPROP 1 LAST PATH I101
J 0
(3950 300);
DISPLAY 0.978723 (3950 300);
PAINT WHITE (3950 300);
DISPLAY INVISIBLE (3950 300);
FORCEPROP 2 LAST CDS_LIB pure_quanta
J 0
(3900 125);
DISPLAY INVISIBLE (3900 125);
FORCEPROP 0 LAST CDS_LOCATION R4188
J 0
(3950 300);
DISPLAY 1.021277 (3950 300);
DISPLAY INVISIBLE (3950 300);
FORCEPROP 0 LAST $SEC 1
J 0
(3950 300);
DISPLAY 0.680851 (3950 300);
PAINT MONO (3950 300);
DISPLAY INVISIBLE (3950 300);
FORCEPROP 0 LAST CDS_SEC 1
J 0
(3950 300);
DISPLAY 1.021277 (3950 300);
DISPLAY INVISIBLE (3950 300);
FORCEADD Q_RES..2
(3900 -475);
FORCEPROP 1 LAST PART_NUMBER CS21002FB06
J 0
(3940 -650);
DISPLAY 0.638298 (3940 -650);
DISPLAY INVISIBLE (3940 -650);
FORCEPROP 1 LAST MATERIAL CHIP
J 0
(3940 -550);
DISPLAY 0.638298 (3940 -550);
FORCEPROP 1 LAST PACK_TYPE 0402LF
J 0
(3940 -600);
DISPLAY 0.638298 (3940 -600);
FORCEPROP 1 LAST VALUE 1K
J 0
(3945 -400);
DISPLAY 0.638298 (3945 -400);
FORCEPROP 1 LAST WATTAGE 1/16W
J 0
(3940 -500);
DISPLAY 0.638298 (3940 -500);
FORCEPROP 1 LAST TOLERANCE 1%
J 0
(3945 -450);
DISPLAY 0.638298 (3945 -450);
FORCEPROP 1 LAST $LOCATION R4189
J 0
(3945 -350);
DISPLAY 0.638298 (3945 -350);
FORCEPROP 1 LASTPIN (3900 -375) $PN 1
J 0
(3905 -413);
DISPLAY 0.787234 (3905 -413);
PAINT MONO (3905 -413);
FORCEPROP 1 LASTPIN (3900 -575) $PN 2
J 0
(3905 -565);
DISPLAY 0.787234 (3905 -565);
PAINT MONO (3905 -565);
FORCEPROP 1 LAST PATH I102
J 0
(3950 -300);
DISPLAY 0.978723 (3950 -300);
PAINT WHITE (3950 -300);
DISPLAY INVISIBLE (3950 -300);
FORCEPROP 2 LAST CDS_LIB pure_quanta
J 0
(3900 -475);
DISPLAY INVISIBLE (3900 -475);
FORCEPROP 0 LAST CDS_LOCATION R4189
J 0
(3950 -300);
DISPLAY 1.021277 (3950 -300);
DISPLAY INVISIBLE (3950 -300);
FORCEPROP 0 LAST $SEC 1
J 0
(3950 -300);
DISPLAY 0.680851 (3950 -300);
PAINT MONO (3950 -300);
DISPLAY INVISIBLE (3950 -300);
FORCEPROP 0 LAST CDS_SEC 1
J 0
(3950 -300);
DISPLAY 1.021277 (3950 -300);
DISPLAY INVISIBLE (3950 -300);
FORCEADD UNIVERSAL_GND..1
(3900 -700);
FORCEPROP 3 LASTPIN (3900 -650) SIG_NAME GND\g
J 0
(3910 -640);
DISPLAY 0.659574 (3910 -640);
PAINT MONO (3910 -640);
DISPLAY INVISIBLE (3910 -640);
FORCEPROP 1 LAST PATH I103
J 0
(3975 -700);
DISPLAY 0.872340 (3975 -700);
PAINT AQUA (3975 -700);
DISPLAY INVISIBLE (3975 -700);
FORCEPROP 2 LAST CDS_LIB logical_power
J 0
(3900 -700);
PAINT MONO (3900 -700);
DISPLAY INVISIBLE (3900 -700);
FORCEPROP 1 LAST HDL_POWER GND
J 1
(3925 -775);
DISPLAY 0.872340 (3925 -775);
PAINT GREEN (3925 -775);
DISPLAY INVISIBLE (3925 -775);
FORCEADD Q_CAP..1
R 2
(2550 475);
FORCEPROP 1 LAST PART_NUMBER CH4104K1B00
J 2
(2500 325);
DISPLAY 0.510638 (2500 325);
DISPLAY INVISIBLE (2500 325);
FORCEPROP 1 LAST PACK_TYPE 0402
J 2
(2500 275);
DISPLAY 0.510638 (2500 275);
FORCEPROP 1 LAST TOLERANCE 10%
J 2
(2500 425);
DISPLAY 0.510638 (2500 425);
FORCEPROP 1 LAST MATERIAL X7R
J 2
(2500 375);
DISPLAY 0.510638 (2500 375);
FORCEPROP 1 LAST VALUE 0.1UF
J 2
(2500 525);
DISPLAY 0.510638 (2500 525);
FORCEPROP 1 LAST VOLTAGE 25V
J 2
(2500 475);
DISPLAY 0.510638 (2500 475);
FORCEPROP 1 LAST $LOCATION C2276
J 2
(2500 575);
DISPLAY 0.978723 (2500 575);
FORCEPROP 1 LASTPIN (2550 575) $PN 1
J 2
(2540 555);
DISPLAY 0.787234 (2540 555);
PAINT MONO (2540 555);
FORCEPROP 1 LASTPIN (2550 375) $PN 2
J 2
(2540 355);
DISPLAY 0.787234 (2540 355);
PAINT MONO (2540 355);
FORCEPROP 1 LAST PATH I104
J 2
(2500 625);
DISPLAY 0.978723 (2500 625);
PAINT WHITE (2500 625);
DISPLAY INVISIBLE (2500 625);
FORCEPROP 2 LAST CDS_LIB pure_quanta
J 0
(2550 475);
DISPLAY INVISIBLE (2550 475);
FORCEPROP 0 LAST CDS_LOCATION C2276
J 0
(2500 625);
DISPLAY 1.021277 (2500 625);
DISPLAY INVISIBLE (2500 625);
FORCEPROP 0 LAST $SEC 1
J 0
(2500 625);
DISPLAY 0.680851 (2500 625);
PAINT MONO (2500 625);
DISPLAY INVISIBLE (2500 625);
FORCEPROP 0 LAST CDS_SEC 1
J 0
(2500 625);
DISPLAY 1.021277 (2500 625);
DISPLAY INVISIBLE (2500 625);
FORCEADD UNIVERSAL_GND..1
(2550 250);
FORCEPROP 3 LASTPIN (2550 300) SIG_NAME GND\g
J 0
(2560 310);
DISPLAY 0.659574 (2560 310);
PAINT MONO (2560 310);
DISPLAY INVISIBLE (2560 310);
FORCEPROP 1 LAST PATH I105
J 0
(2625 250);
DISPLAY 0.872340 (2625 250);
PAINT AQUA (2625 250);
DISPLAY INVISIBLE (2625 250);
FORCEPROP 2 LAST CDS_LIB logical_power
J 0
(2550 250);
DISPLAY INVISIBLE (2550 250);
FORCEPROP 1 LAST HDL_POWER GND
J 1
(2575 175);
DISPLAY 0.872340 (2575 175);
PAINT GREEN (2575 175);
DISPLAY INVISIBLE (2575 175);
FORCEADD UNIVERSAL_GND..1
(1625 -450);
FORCEPROP 3 LASTPIN (1625 -400) SIG_NAME GND\g
J 0
(1635 -390);
DISPLAY 0.659574 (1635 -390);
PAINT MONO (1635 -390);
DISPLAY INVISIBLE (1635 -390);
FORCEPROP 1 LAST PATH I106
J 0
(1700 -450);
DISPLAY 0.872340 (1700 -450);
PAINT AQUA (1700 -450);
DISPLAY INVISIBLE (1700 -450);
FORCEPROP 1 LAST HDL_POWER GND
J 1
(1650 -525);
DISPLAY 0.872340 (1650 -525);
PAINT GREEN (1650 -525);
DISPLAY INVISIBLE (1650 -525);
FORCEPROP 2 LAST CDS_LIB logical_power
J 0
(1625 -450);
DISPLAY INVISIBLE (1625 -450);
FORCEADD Q_RES..1
(300 125);
FORCEPROP 1 LAST PART_NUMBER CS03322FB03
J 0
(175 225);
DISPLAY 0.638298 (175 225);
DISPLAY INVISIBLE (175 225);
FORCEPROP 1 LAST WATTAGE 1/16W
J 2
(-50 125);
DISPLAY 0.638298 (-50 125);
FORCEPROP 1 LAST MATERIAL CHIP
J 0
(-25 125);
DISPLAY 0.638298 (-25 125);
FORCEPROP 1 LAST TOLERANCE 1%
J 0
(550 125);
DISPLAY 0.638298 (550 125);
FORCEPROP 1 LAST VALUE 33.2
J 2
(525 125);
DISPLAY 0.638298 (525 125);
FORCEPROP 1 LAST PACK_TYPE 0402LF
J 0
(650 125);
DISPLAY 0.638298 (650 125);
FORCEPROP 1 LAST $LOCATION R4182
J 0
(100 125);
DISPLAY 0.638298 (100 125);
FORCEPROP 1 LASTPIN (200 125) $PN 1
J 0
(212 137);
DISPLAY 0.787234 (212 137);
PAINT MONO (212 137);
FORCEPROP 1 LASTPIN (400 125) $PN 2
J 0
(362 137);
DISPLAY 0.787234 (362 137);
PAINT MONO (362 137);
FORCEPROP 2 LAST CDS_LIB pure_quanta
J 0
(300 125);
DISPLAY INVISIBLE (300 125);
FORCEPROP 1 LAST PATH I107
J 0
(250 275);
DISPLAY 0.978723 (250 275);
PAINT WHITE (250 275);
DISPLAY INVISIBLE (250 275);
FORCEPROP 0 LAST CDS_LOCATION R4182
J 0
(650 175);
DISPLAY 1.021277 (650 175);
DISPLAY INVISIBLE (650 175);
FORCEPROP 0 LAST $SEC 1
J 0
(650 175);
DISPLAY 0.680851 (650 175);
PAINT MONO (650 175);
DISPLAY INVISIBLE (650 175);
FORCEPROP 0 LAST CDS_SEC 1
J 0
(650 175);
DISPLAY 1.021277 (650 175);
DISPLAY INVISIBLE (650 175);
FORCEADD Q_RES..1
(300 -175);
FORCEPROP 1 LAST PART_NUMBER CS00002JB13
J 0
(25 -300);
DISPLAY 0.723404 (25 -300);
PAINT WHITE (25 -300);
DISPLAY INVISIBLE (25 -300);
FORCEPROP 1 LAST VALUE 0
J 2
(450 -175);
DISPLAY 0.574468 (450 -175);
FORCEPROP 1 LAST PACK_TYPE 0402LF
J 0
(600 -175);
DISPLAY 0.574468 (600 -175);
FORCEPROP 1 LAST MATERIAL CHIP
J 0
(475 -175);
DISPLAY 0.574468 (475 -175);
FORCEPROP 1 LAST $LOCATION R4214
J 0
(100 -175);
DISPLAY 0.638298 (100 -175);
FORCEPROP 1 LASTPIN (200 -175) $PN 1
J 0
(212 -163);
DISPLAY 0.787234 (212 -163);
PAINT MONO (212 -163);
FORCEPROP 1 LASTPIN (400 -175) $PN 2
J 0
(362 -163);
DISPLAY 0.787234 (362 -163);
PAINT MONO (362 -163);
FORCEPROP 2 LAST CDS_LIB pure_quanta
J 0
(300 -175);
DISPLAY INVISIBLE (300 -175);
FORCEPROP 1 LAST WATTAGE 1/16W
J 2
(375 -250);
DISPLAY 0.723404 (375 -250);
PAINT SKYBLUE (375 -250);
DISPLAY INVISIBLE (375 -250);
FORCEPROP 1 LAST TOLERANCE 5%
J 0
(100 -250);
DISPLAY 0.723404 (100 -250);
PAINT SKYBLUE (100 -250);
DISPLAY INVISIBLE (100 -250);
FORCEPROP 1 LAST PATH I108
J 0
(250 -25);
DISPLAY 0.978723 (250 -25);
PAINT WHITE (250 -25);
DISPLAY INVISIBLE (250 -25);
FORCEPROP 0 LAST CDS_LOCATION R4214
J 0
(600 -125);
DISPLAY 1.021277 (600 -125);
DISPLAY INVISIBLE (600 -125);
FORCEPROP 0 LAST $SEC 1
J 0
(600 -125);
DISPLAY 0.680851 (600 -125);
PAINT MONO (600 -125);
DISPLAY INVISIBLE (600 -125);
FORCEPROP 0 LAST CDS_SEC 1
J 0
(600 -125);
DISPLAY 1.021277 (600 -125);
DISPLAY INVISIBLE (600 -125);
FORCEADD Q_RES..1
(300 -25);
FORCEPROP 1 LAST PART_NUMBER CS03322FB03
J 0
(150 200);
DISPLAY 0.638298 (150 200);
DISPLAY INVISIBLE (150 200);
FORCEPROP 1 LAST MATERIAL CHIP
J 0
(-25 -25);
DISPLAY 0.638298 (-25 -25);
FORCEPROP 1 LAST VALUE 33.2
J 2
(525 -25);
DISPLAY 0.638298 (525 -25);
FORCEPROP 1 LAST TOLERANCE 1%
J 0
(550 -25);
DISPLAY 0.638298 (550 -25);
FORCEPROP 1 LAST WATTAGE 1/16W
J 2
(-50 -25);
DISPLAY 0.638298 (-50 -25);
FORCEPROP 1 LAST PACK_TYPE 0402LF
J 0
(650 -25);
DISPLAY 0.638298 (650 -25);
FORCEPROP 1 LAST $LOCATION R4179
J 0
(100 -25);
DISPLAY 0.638298 (100 -25);
FORCEPROP 1 LASTPIN (200 -25) $PN 1
J 0
(212 -13);
DISPLAY 0.787234 (212 -13);
PAINT MONO (212 -13);
FORCEPROP 1 LASTPIN (400 -25) $PN 2
J 0
(362 -13);
DISPLAY 0.787234 (362 -13);
PAINT MONO (362 -13);
FORCEPROP 2 LAST CDS_LIB pure_quanta
J 0
(300 -25);
DISPLAY INVISIBLE (300 -25);
FORCEPROP 1 LAST PATH I109
J 0
(250 125);
DISPLAY 0.978723 (250 125);
PAINT WHITE (250 125);
DISPLAY INVISIBLE (250 125);
FORCEPROP 0 LAST CDS_LOCATION R4179
J 0
(650 25);
DISPLAY 1.021277 (650 25);
DISPLAY INVISIBLE (650 25);
FORCEPROP 0 LAST $SEC 1
J 0
(650 25);
DISPLAY 0.680851 (650 25);
PAINT MONO (650 25);
DISPLAY INVISIBLE (650 25);
FORCEPROP 0 LAST CDS_SEC 1
J 0
(650 25);
DISPLAY 1.021277 (650 25);
DISPLAY INVISIBLE (650 25);
FORCEADD OFFPAGE..1
(-950 125);
FORCEPROP 2 LAST $XR0 233 
J 0
(-1232 125);
DISPLAY 0.638298 (-1232 125);
PAINT MONO (-1232 125);
FORCEPROP 2 LAST CDS_LIB standard
J 0
(-950 125);
DISPLAY INVISIBLE (-950 125);
FORCEPROP 1 LAST COMMENT_BODY TRUE
J 0
(-825 25);
DISPLAY 0.872340 (-825 25);
PAINT GREEN (-825 25);
DISPLAY INVISIBLE (-825 25);
FORCEPROP 1 LAST OFFPAGE TRUE
J 0
(-625 0);
DISPLAY 0.872340 (-625 0);
PAINT GREEN (-625 0);
DISPLAY INVISIBLE (-625 0);
FORCEPROP 2 LAST PATH I110
J 0
(-1125 175);
DISPLAY 1.021277 (-1125 175);
DISPLAY INVISIBLE (-1125 175);
FORCEADD OFFPAGE..3
R 2
(-950 -25);
FORCEPROP 2 LAST $XR0 233 
J 0
(-1230 -25);
DISPLAY 0.638298 (-1230 -25);
PAINT MONO (-1230 -25);
FORCEPROP 1 LAST COMMENT_BODY TRUE
J 2
(-900 -125);
DISPLAY 0.872340 (-900 -125);
PAINT GREEN (-900 -125);
DISPLAY INVISIBLE (-900 -125);
FORCEPROP 1 LAST OFFPAGE TRUE
J 2
(-1275 -150);
DISPLAY 0.872340 (-1275 -150);
DISPLAY INVISIBLE (-1275 -150);
FORCEPROP 2 LAST CDS_LIB standard
J 0
(-950 -25);
DISPLAY INVISIBLE (-950 -25);
FORCEPROP 2 LAST PATH I111
J 0
(-1150 25);
DISPLAY 1.021277 (-1150 25);
DISPLAY INVISIBLE (-1150 25);
FORCEADD OFFPAGE..3
R 2
(-975 -1500);
FORCEPROP 2 LAST $XR0 233 
J 0
(-1285 -1500);
DISPLAY 0.638298 (-1285 -1500);
PAINT MONO (-1285 -1500);
FORCEPROP 2 LAST CDS_LIB standard
J 0
(-975 -1500);
DISPLAY INVISIBLE (-975 -1500);
FORCEPROP 1 LAST OFFPAGE TRUE
J 2
(-1300 -1625);
DISPLAY 0.872340 (-1300 -1625);
DISPLAY INVISIBLE (-1300 -1625);
FORCEPROP 1 LAST COMMENT_BODY TRUE
J 2
(-925 -1600);
DISPLAY 0.872340 (-925 -1600);
PAINT GREEN (-925 -1600);
DISPLAY INVISIBLE (-925 -1600);
FORCEPROP 2 LAST PATH I112
J 0
(-1175 -1450);
DISPLAY 1.021277 (-1175 -1450);
DISPLAY INVISIBLE (-1175 -1450);
FORCEADD OFFPAGE..1
(-975 -1350);
FORCEPROP 2 LAST $XR0 233 
J 0
(-1257 -1350);
DISPLAY 0.638298 (-1257 -1350);
PAINT MONO (-1257 -1350);
FORCEPROP 1 LAST OFFPAGE TRUE
J 0
(-650 -1475);
DISPLAY 0.872340 (-650 -1475);
PAINT GREEN (-650 -1475);
DISPLAY INVISIBLE (-650 -1475);
FORCEPROP 1 LAST COMMENT_BODY TRUE
J 0
(-850 -1450);
DISPLAY 0.872340 (-850 -1450);
PAINT GREEN (-850 -1450);
DISPLAY INVISIBLE (-850 -1450);
FORCEPROP 2 LAST CDS_LIB standard
J 0
(-975 -1350);
DISPLAY INVISIBLE (-975 -1350);
FORCEPROP 2 LAST PATH I113
J 0
(-1150 -1300);
DISPLAY 1.021277 (-1150 -1300);
DISPLAY INVISIBLE (-1150 -1300);
FORCEADD Q_RES..1
(275 -1500);
FORCEPROP 1 LAST PART_NUMBER CS03322FB03
J 0
(100 -1300);
DISPLAY 0.638298 (100 -1300);
DISPLAY INVISIBLE (100 -1300);
FORCEPROP 1 LAST TOLERANCE 1%
J 0
(525 -1500);
DISPLAY 0.638298 (525 -1500);
FORCEPROP 1 LAST WATTAGE 1/16W
J 2
(-75 -1500);
DISPLAY 0.638298 (-75 -1500);
FORCEPROP 1 LAST MATERIAL CHIP
J 0
(-50 -1500);
DISPLAY 0.638298 (-50 -1500);
FORCEPROP 1 LAST PACK_TYPE 0402LF
J 0
(625 -1500);
DISPLAY 0.638298 (625 -1500);
FORCEPROP 1 LAST VALUE 33.2
J 2
(500 -1500);
DISPLAY 0.638298 (500 -1500);
FORCEPROP 1 LAST $LOCATION R4178
J 0
(75 -1500);
DISPLAY 0.638298 (75 -1500);
FORCEPROP 1 LASTPIN (175 -1500) $PN 1
J 0
(187 -1488);
DISPLAY 0.787234 (187 -1488);
PAINT MONO (187 -1488);
FORCEPROP 1 LASTPIN (375 -1500) $PN 2
J 0
(337 -1488);
DISPLAY 0.787234 (337 -1488);
PAINT MONO (337 -1488);
FORCEPROP 2 LAST CDS_LIB pure_quanta
J 0
(275 -1500);
DISPLAY INVISIBLE (275 -1500);
FORCEPROP 1 LAST PATH I114
J 0
(225 -1350);
DISPLAY 0.978723 (225 -1350);
PAINT WHITE (225 -1350);
DISPLAY INVISIBLE (225 -1350);
FORCEPROP 0 LAST CDS_LOCATION R4178
J 0
(625 -1450);
DISPLAY 1.021277 (625 -1450);
DISPLAY INVISIBLE (625 -1450);
FORCEPROP 0 LAST $SEC 1
J 0
(625 -1450);
DISPLAY 0.680851 (625 -1450);
PAINT MONO (625 -1450);
DISPLAY INVISIBLE (625 -1450);
FORCEPROP 0 LAST CDS_SEC 1
J 0
(625 -1450);
DISPLAY 1.021277 (625 -1450);
DISPLAY INVISIBLE (625 -1450);
FORCEADD Q_RES..1
(275 -1650);
FORCEPROP 1 LAST PART_NUMBER CS00002JB13
J 0
(0 -1775);
DISPLAY 0.723404 (0 -1775);
PAINT WHITE (0 -1775);
DISPLAY INVISIBLE (0 -1775);
FORCEPROP 1 LAST MATERIAL CHIP
J 0
(450 -1650);
DISPLAY 0.574468 (450 -1650);
FORCEPROP 1 LAST VALUE 0
J 2
(425 -1650);
DISPLAY 0.574468 (425 -1650);
FORCEPROP 1 LAST PACK_TYPE 0402LF
J 0
(575 -1650);
DISPLAY 0.574468 (575 -1650);
FORCEPROP 1 LAST $LOCATION R4213
J 0
(75 -1650);
DISPLAY 0.638298 (75 -1650);
FORCEPROP 1 LASTPIN (175 -1650) $PN 1
J 0
(187 -1638);
DISPLAY 0.787234 (187 -1638);
PAINT MONO (187 -1638);
FORCEPROP 1 LASTPIN (375 -1650) $PN 2
J 0
(337 -1638);
DISPLAY 0.787234 (337 -1638);
PAINT MONO (337 -1638);
FORCEPROP 1 LAST TOLERANCE 5%
J 0
(75 -1725);
DISPLAY 0.723404 (75 -1725);
PAINT SKYBLUE (75 -1725);
DISPLAY INVISIBLE (75 -1725);
FORCEPROP 1 LAST WATTAGE 1/16W
J 2
(350 -1725);
DISPLAY 0.723404 (350 -1725);
PAINT SKYBLUE (350 -1725);
DISPLAY INVISIBLE (350 -1725);
FORCEPROP 2 LAST CDS_LIB pure_quanta
J 0
(275 -1650);
DISPLAY INVISIBLE (275 -1650);
FORCEPROP 1 LAST PATH I115
J 0
(225 -1500);
DISPLAY 0.978723 (225 -1500);
PAINT WHITE (225 -1500);
DISPLAY INVISIBLE (225 -1500);
FORCEPROP 0 LAST CDS_LOCATION R4213
J 0
(575 -1600);
DISPLAY 1.021277 (575 -1600);
DISPLAY INVISIBLE (575 -1600);
FORCEPROP 0 LAST $SEC 1
J 0
(575 -1600);
DISPLAY 0.680851 (575 -1600);
PAINT MONO (575 -1600);
DISPLAY INVISIBLE (575 -1600);
FORCEPROP 0 LAST CDS_SEC 1
J 0
(575 -1600);
DISPLAY 1.021277 (575 -1600);
DISPLAY INVISIBLE (575 -1600);
FORCEADD Q_RES..1
(275 -1350);
FORCEPROP 1 LAST PART_NUMBER CS03322FB03
J 0
(150 -1250);
DISPLAY 0.638298 (150 -1250);
DISPLAY INVISIBLE (150 -1250);
FORCEPROP 1 LAST MATERIAL CHIP
J 0
(-50 -1350);
DISPLAY 0.638298 (-50 -1350);
FORCEPROP 1 LAST VALUE 33.2
J 2
(500 -1350);
DISPLAY 0.638298 (500 -1350);
FORCEPROP 1 LAST TOLERANCE 1%
J 0
(525 -1350);
DISPLAY 0.638298 (525 -1350);
FORCEPROP 1 LAST WATTAGE 1/16W
J 2
(-75 -1350);
DISPLAY 0.638298 (-75 -1350);
FORCEPROP 1 LAST PACK_TYPE 0402LF
J 0
(625 -1350);
DISPLAY 0.638298 (625 -1350);
FORCEPROP 1 LAST $LOCATION R4181
J 0
(75 -1350);
DISPLAY 0.638298 (75 -1350);
FORCEPROP 1 LASTPIN (175 -1350) $PN 1
J 0
(187 -1338);
DISPLAY 0.787234 (187 -1338);
PAINT MONO (187 -1338);
FORCEPROP 1 LASTPIN (375 -1350) $PN 2
J 0
(337 -1338);
DISPLAY 0.787234 (337 -1338);
PAINT MONO (337 -1338);
FORCEPROP 2 LAST CDS_LIB pure_quanta
J 0
(275 -1350);
DISPLAY INVISIBLE (275 -1350);
FORCEPROP 1 LAST PATH I116
J 0
(225 -1200);
DISPLAY 0.978723 (225 -1200);
PAINT WHITE (225 -1200);
DISPLAY INVISIBLE (225 -1200);
FORCEPROP 0 LAST CDS_LOCATION R4181
J 0
(625 -1300);
DISPLAY 1.021277 (625 -1300);
DISPLAY INVISIBLE (625 -1300);
FORCEPROP 0 LAST $SEC 1
J 0
(625 -1300);
DISPLAY 0.680851 (625 -1300);
PAINT MONO (625 -1300);
DISPLAY INVISIBLE (625 -1300);
FORCEPROP 0 LAST CDS_SEC 1
J 0
(625 -1300);
DISPLAY 1.021277 (625 -1300);
DISPLAY INVISIBLE (625 -1300);
FORCEADD UNIVERSAL_GND..1
(1600 -1925);
FORCEPROP 3 LASTPIN (1600 -1875) SIG_NAME GND\g
J 0
(1610 -1865);
DISPLAY 0.659574 (1610 -1865);
PAINT MONO (1610 -1865);
DISPLAY INVISIBLE (1610 -1865);
FORCEPROP 1 LAST PATH I117
J 0
(1675 -1925);
DISPLAY 0.872340 (1675 -1925);
PAINT AQUA (1675 -1925);
DISPLAY INVISIBLE (1675 -1925);
FORCEPROP 2 LAST CDS_LIB logical_power
J 0
(1600 -1925);
DISPLAY INVISIBLE (1600 -1925);
FORCEPROP 1 LAST HDL_POWER GND
J 1
(1625 -2000);
DISPLAY 0.872340 (1625 -2000);
PAINT GREEN (1625 -2000);
DISPLAY INVISIBLE (1625 -2000);
FORCEADD UNIVERSAL_GND..1
(2525 -1225);
FORCEPROP 3 LASTPIN (2525 -1175) SIG_NAME GND\g
J 0
(2535 -1165);
DISPLAY 0.659574 (2535 -1165);
PAINT MONO (2535 -1165);
DISPLAY INVISIBLE (2535 -1165);
FORCEPROP 1 LAST PATH I118
J 0
(2600 -1225);
DISPLAY 0.872340 (2600 -1225);
PAINT AQUA (2600 -1225);
DISPLAY INVISIBLE (2600 -1225);
FORCEPROP 1 LAST HDL_POWER GND
J 1
(2550 -1300);
DISPLAY 0.872340 (2550 -1300);
PAINT GREEN (2550 -1300);
DISPLAY INVISIBLE (2550 -1300);
FORCEPROP 2 LAST CDS_LIB logical_power
J 0
(2525 -1225);
DISPLAY INVISIBLE (2525 -1225);
FORCEADD Q_CAP..1
R 2
(2525 -1000);
FORCEPROP 1 LAST PART_NUMBER CH4104K1B00
J 2
(2475 -1150);
DISPLAY 0.510638 (2475 -1150);
DISPLAY INVISIBLE (2475 -1150);
FORCEPROP 1 LAST MATERIAL X7R
J 2
(2475 -1100);
DISPLAY 0.510638 (2475 -1100);
FORCEPROP 1 LAST VOLTAGE 25V
J 2
(2475 -1000);
DISPLAY 0.510638 (2475 -1000);
FORCEPROP 1 LAST VALUE 0.1UF
J 2
(2475 -950);
DISPLAY 0.510638 (2475 -950);
FORCEPROP 1 LAST PACK_TYPE 0402
J 2
(2475 -1200);
DISPLAY 0.510638 (2475 -1200);
FORCEPROP 1 LAST TOLERANCE 10%
J 2
(2475 -1050);
DISPLAY 0.510638 (2475 -1050);
FORCEPROP 1 LAST $LOCATION C2275
J 2
(2475 -900);
DISPLAY 0.978723 (2475 -900);
FORCEPROP 1 LASTPIN (2525 -900) $PN 1
J 2
(2515 -920);
DISPLAY 0.787234 (2515 -920);
PAINT MONO (2515 -920);
FORCEPROP 1 LASTPIN (2525 -1100) $PN 2
J 2
(2515 -1120);
DISPLAY 0.787234 (2515 -1120);
PAINT MONO (2515 -1120);
FORCEPROP 1 LAST PATH I119
J 2
(2475 -850);
DISPLAY 0.978723 (2475 -850);
PAINT WHITE (2475 -850);
DISPLAY INVISIBLE (2475 -850);
FORCEPROP 2 LAST CDS_LIB pure_quanta
J 0
(2525 -1000);
DISPLAY INVISIBLE (2525 -1000);
FORCEPROP 0 LAST CDS_LOCATION C2275
J 0
(2475 -850);
DISPLAY 1.021277 (2475 -850);
DISPLAY INVISIBLE (2475 -850);
FORCEPROP 0 LAST $SEC 1
J 0
(2475 -850);
DISPLAY 0.680851 (2475 -850);
PAINT MONO (2475 -850);
DISPLAY INVISIBLE (2475 -850);
FORCEPROP 0 LAST CDS_SEC 1
J 0
(2475 -850);
DISPLAY 1.021277 (2475 -850);
DISPLAY INVISIBLE (2475 -850);
FORCEADD UNIVERSAL_GND..1
(3875 -2175);
FORCEPROP 3 LASTPIN (3875 -2125) SIG_NAME GND\g
J 0
(3885 -2115);
DISPLAY 0.659574 (3885 -2115);
PAINT MONO (3885 -2115);
DISPLAY INVISIBLE (3885 -2115);
FORCEPROP 1 LAST PATH I120
J 0
(3950 -2175);
DISPLAY 0.872340 (3950 -2175);
PAINT AQUA (3950 -2175);
DISPLAY INVISIBLE (3950 -2175);
FORCEPROP 1 LAST HDL_POWER GND
J 1
(3900 -2250);
DISPLAY 0.872340 (3900 -2250);
PAINT GREEN (3900 -2250);
DISPLAY INVISIBLE (3900 -2250);
FORCEPROP 2 LAST CDS_LIB logical_power
J 0
(3875 -2175);
PAINT MONO (3875 -2175);
DISPLAY INVISIBLE (3875 -2175);
FORCEADD Q_RES..2
(3875 -1950);
FORCEPROP 1 LAST PART_NUMBER CS21002FB06
J 0
(3915 -2125);
DISPLAY 0.638298 (3915 -2125);
DISPLAY INVISIBLE (3915 -2125);
FORCEPROP 1 LAST TOLERANCE 1%
J 0
(3920 -1925);
DISPLAY 0.638298 (3920 -1925);
FORCEPROP 1 LAST WATTAGE 1/16W
J 0
(3915 -1975);
DISPLAY 0.638298 (3915 -1975);
FORCEPROP 1 LAST VALUE 1K
J 0
(3920 -1875);
DISPLAY 0.638298 (3920 -1875);
FORCEPROP 1 LAST PACK_TYPE 0402LF
J 0
(3915 -2075);
DISPLAY 0.638298 (3915 -2075);
FORCEPROP 1 LAST MATERIAL CHIP
J 0
(3915 -2025);
DISPLAY 0.638298 (3915 -2025);
FORCEPROP 1 LAST $LOCATION R4187
J 0
(3920 -1825);
DISPLAY 0.638298 (3920 -1825);
FORCEPROP 1 LASTPIN (3875 -1850) $PN 1
J 0
(3880 -1888);
DISPLAY 0.787234 (3880 -1888);
PAINT MONO (3880 -1888);
FORCEPROP 1 LASTPIN (3875 -2050) $PN 2
J 0
(3880 -2040);
DISPLAY 0.787234 (3880 -2040);
PAINT MONO (3880 -2040);
FORCEPROP 1 LAST PATH I121
J 0
(3925 -1775);
DISPLAY 0.978723 (3925 -1775);
PAINT WHITE (3925 -1775);
DISPLAY INVISIBLE (3925 -1775);
FORCEPROP 2 LAST CDS_LIB pure_quanta
J 0
(3875 -1950);
DISPLAY INVISIBLE (3875 -1950);
FORCEPROP 0 LAST CDS_LOCATION R4187
J 0
(3925 -1775);
DISPLAY 1.021277 (3925 -1775);
DISPLAY INVISIBLE (3925 -1775);
FORCEPROP 0 LAST $SEC 1
J 0
(3925 -1775);
DISPLAY 0.680851 (3925 -1775);
PAINT MONO (3925 -1775);
DISPLAY INVISIBLE (3925 -1775);
FORCEPROP 0 LAST CDS_SEC 1
J 0
(3925 -1775);
DISPLAY 1.021277 (3925 -1775);
DISPLAY INVISIBLE (3925 -1775);
FORCEADD Q_RES..2
(3875 -1350);
FORCEPROP 1 LAST PART_NUMBER CS21002FB06
J 0
(3915 -1525);
DISPLAY 0.638298 (3915 -1525);
DISPLAY INVISIBLE (3915 -1525);
FORCEPROP 1 LAST PACK_TYPE 0402LF
J 0
(3915 -1475);
DISPLAY 0.638298 (3915 -1475);
FORCEPROP 1 LAST MATERIAL EMPTY
J 0
(3915 -1425);
DISPLAY 0.638298 (3915 -1425);
PAINT RED (3915 -1425);
FORCEPROP 1 LAST VALUE 1K
J 0
(3920 -1275);
DISPLAY 0.638298 (3920 -1275);
FORCEPROP 1 LAST WATTAGE 1/16W
J 0
(3915 -1375);
DISPLAY 0.638298 (3915 -1375);
FORCEPROP 1 LAST TOLERANCE 1%
J 0
(3920 -1325);
DISPLAY 0.638298 (3920 -1325);
FORCEPROP 1 LAST $LOCATION R4186
J 0
(3920 -1225);
DISPLAY 0.638298 (3920 -1225);
FORCEPROP 1 LASTPIN (3875 -1250) $PN 1
J 0
(3880 -1288);
DISPLAY 0.787234 (3880 -1288);
PAINT MONO (3880 -1288);
FORCEPROP 1 LASTPIN (3875 -1450) $PN 2
J 0
(3880 -1440);
DISPLAY 0.787234 (3880 -1440);
PAINT MONO (3880 -1440);
FORCEPROP 1 LAST PATH I122
J 0
(3925 -1175);
DISPLAY 0.978723 (3925 -1175);
PAINT WHITE (3925 -1175);
DISPLAY INVISIBLE (3925 -1175);
FORCEPROP 2 LAST CDS_LIB pure_quanta
J 0
(3875 -1350);
DISPLAY INVISIBLE (3875 -1350);
FORCEPROP 0 LAST CDS_LOCATION R4186
J 0
(3925 -1175);
DISPLAY 1.021277 (3925 -1175);
DISPLAY INVISIBLE (3925 -1175);
FORCEPROP 0 LAST $SEC 1
J 0
(3925 -1175);
DISPLAY 0.680851 (3925 -1175);
PAINT MONO (3925 -1175);
DISPLAY INVISIBLE (3925 -1175);
FORCEPROP 0 LAST CDS_SEC 1
J 0
(3925 -1175);
DISPLAY 1.021277 (3925 -1175);
DISPLAY INVISIBLE (3925 -1175);
FORCEADD UNIVERSAL_POWER..1
(2525 -675);
FORCEPROP 3 LASTPIN (2525 -725) SIG_NAME P3V3_AUX\g
J 0
(2535 -715);
DISPLAY 0.659574 (2535 -715);
PAINT MONO (2535 -715);
DISPLAY INVISIBLE (2535 -715);
FORCEPROP 1 LAST HDL_POWER P3V3_AUX
J 1
(2525 -625);
DISPLAY 0.872340 (2525 -625);
PAINT GREEN (2525 -625);
FORCEPROP 1 LAST PATH I123
J 0
(2575 -650);
DISPLAY 0.872340 (2575 -650);
PAINT AQUA (2575 -650);
DISPLAY INVISIBLE (2575 -650);
FORCEPROP 2 LAST CDS_LIB logical_power
J 0
(2525 -675);
DISPLAY INVISIBLE (2525 -675);
FORCEADD UNIVERSAL_GND..1
(4125 -2175);
FORCEPROP 3 LASTPIN (4125 -2125) SIG_NAME GND\g
J 0
(4135 -2115);
DISPLAY 0.659574 (4135 -2115);
PAINT MONO (4135 -2115);
DISPLAY INVISIBLE (4135 -2115);
FORCEPROP 1 LAST PATH I124
J 0
(4200 -2175);
DISPLAY 0.872340 (4200 -2175);
PAINT AQUA (4200 -2175);
DISPLAY INVISIBLE (4200 -2175);
FORCEPROP 1 LAST HDL_POWER GND
J 1
(4150 -2250);
DISPLAY 0.872340 (4150 -2250);
PAINT GREEN (4150 -2250);
DISPLAY INVISIBLE (4150 -2250);
FORCEPROP 2 LAST CDS_LIB logical_power
J 0
(4125 -2175);
PAINT MONO (4125 -2175);
DISPLAY INVISIBLE (4125 -2175);
FORCEADD Q_RES..2
(4125 -1950);
FORCEPROP 1 LAST PART_NUMBER CS21002FB06
J 0
(4165 -2125);
DISPLAY 0.638298 (4165 -2125);
DISPLAY INVISIBLE (4165 -2125);
FORCEPROP 1 LAST TOLERANCE 1%
J 0
(4170 -1925);
DISPLAY 0.638298 (4170 -1925);
FORCEPROP 1 LAST WATTAGE 1/16W
J 0
(4165 -1975);
DISPLAY 0.638298 (4165 -1975);
FORCEPROP 1 LAST VALUE 1K
J 0
(4170 -1875);
DISPLAY 0.638298 (4170 -1875);
FORCEPROP 1 LAST PACK_TYPE 0402LF
J 0
(4165 -2075);
DISPLAY 0.638298 (4165 -2075);
FORCEPROP 1 LAST MATERIAL CHIP
J 0
(4165 -2025);
DISPLAY 0.638298 (4165 -2025);
FORCEPROP 1 LAST $LOCATION R4195
J 0
(4170 -1825);
DISPLAY 0.638298 (4170 -1825);
FORCEPROP 1 LASTPIN (4125 -1850) $PN 1
J 0
(4130 -1888);
DISPLAY 0.787234 (4130 -1888);
PAINT MONO (4130 -1888);
FORCEPROP 1 LASTPIN (4125 -2050) $PN 2
J 0
(4130 -2040);
DISPLAY 0.787234 (4130 -2040);
PAINT MONO (4130 -2040);
FORCEPROP 1 LAST PATH I125
J 0
(4175 -1775);
DISPLAY 0.978723 (4175 -1775);
PAINT WHITE (4175 -1775);
DISPLAY INVISIBLE (4175 -1775);
FORCEPROP 2 LAST CDS_LIB pure_quanta
J 0
(4125 -1950);
DISPLAY INVISIBLE (4125 -1950);
FORCEPROP 0 LAST CDS_LOCATION R4195
J 0
(4175 -1775);
DISPLAY 1.021277 (4175 -1775);
DISPLAY INVISIBLE (4175 -1775);
FORCEPROP 0 LAST $SEC 1
J 0
(4175 -1775);
DISPLAY 0.680851 (4175 -1775);
PAINT MONO (4175 -1775);
DISPLAY INVISIBLE (4175 -1775);
FORCEPROP 0 LAST CDS_SEC 1
J 0
(4175 -1775);
DISPLAY 1.021277 (4175 -1775);
DISPLAY INVISIBLE (4175 -1775);
FORCEADD UNIVERSAL_GND..1
(4375 -2175);
FORCEPROP 3 LASTPIN (4375 -2125) SIG_NAME GND\g
J 0
(4385 -2115);
DISPLAY 0.659574 (4385 -2115);
PAINT MONO (4385 -2115);
DISPLAY INVISIBLE (4385 -2115);
FORCEPROP 1 LAST PATH I126
J 0
(4450 -2175);
DISPLAY 0.872340 (4450 -2175);
PAINT AQUA (4450 -2175);
DISPLAY INVISIBLE (4450 -2175);
FORCEPROP 1 LAST HDL_POWER GND
J 1
(4400 -2250);
DISPLAY 0.872340 (4400 -2250);
PAINT GREEN (4400 -2250);
DISPLAY INVISIBLE (4400 -2250);
FORCEPROP 2 LAST CDS_LIB logical_power
J 0
(4375 -2175);
PAINT MONO (4375 -2175);
DISPLAY INVISIBLE (4375 -2175);
FORCEADD Q_RES..2
(4375 -1950);
FORCEPROP 1 LAST PART_NUMBER CS21002FB06
J 0
(4415 -2125);
DISPLAY 0.638298 (4415 -2125);
DISPLAY INVISIBLE (4415 -2125);
FORCEPROP 1 LAST TOLERANCE 1%
J 0
(4420 -1925);
DISPLAY 0.638298 (4420 -1925);
FORCEPROP 1 LAST VALUE 1K
J 0
(4420 -1875);
DISPLAY 0.638298 (4420 -1875);
FORCEPROP 1 LAST WATTAGE 1/16W
J 0
(4415 -1975);
DISPLAY 0.638298 (4415 -1975);
FORCEPROP 1 LAST PACK_TYPE 0402LF
J 0
(4415 -2075);
DISPLAY 0.638298 (4415 -2075);
FORCEPROP 1 LAST MATERIAL CHIP
J 0
(4415 -2025);
DISPLAY 0.638298 (4415 -2025);
FORCEPROP 1 LAST $LOCATION R4203
J 0
(4420 -1825);
DISPLAY 0.638298 (4420 -1825);
FORCEPROP 1 LASTPIN (4375 -1850) $PN 1
J 0
(4380 -1888);
DISPLAY 0.787234 (4380 -1888);
PAINT MONO (4380 -1888);
FORCEPROP 1 LASTPIN (4375 -2050) $PN 2
J 0
(4380 -2040);
DISPLAY 0.787234 (4380 -2040);
PAINT MONO (4380 -2040);
FORCEPROP 1 LAST PATH I127
J 0
(4425 -1775);
DISPLAY 0.978723 (4425 -1775);
PAINT WHITE (4425 -1775);
DISPLAY INVISIBLE (4425 -1775);
FORCEPROP 2 LAST CDS_LIB pure_quanta
J 0
(4375 -1950);
DISPLAY INVISIBLE (4375 -1950);
FORCEPROP 0 LAST CDS_LOCATION R4203
J 0
(4425 -1775);
DISPLAY 1.021277 (4425 -1775);
DISPLAY INVISIBLE (4425 -1775);
FORCEPROP 0 LAST $SEC 1
J 0
(4425 -1775);
DISPLAY 0.680851 (4425 -1775);
PAINT MONO (4425 -1775);
DISPLAY INVISIBLE (4425 -1775);
FORCEPROP 0 LAST CDS_SEC 1
J 0
(4425 -1775);
DISPLAY 1.021277 (4425 -1775);
DISPLAY INVISIBLE (4425 -1775);
FORCEADD Q_RES..2
(4125 -1350);
FORCEPROP 1 LAST PART_NUMBER CS21002FB06
J 0
(4165 -1525);
DISPLAY 0.638298 (4165 -1525);
DISPLAY INVISIBLE (4165 -1525);
FORCEPROP 1 LAST PACK_TYPE 0402LF
J 0
(4165 -1475);
DISPLAY 0.638298 (4165 -1475);
FORCEPROP 1 LAST MATERIAL EMPTY
J 0
(4165 -1425);
DISPLAY 0.638298 (4165 -1425);
PAINT RED (4165 -1425);
FORCEPROP 1 LAST VALUE 1K
J 0
(4170 -1275);
DISPLAY 0.638298 (4170 -1275);
FORCEPROP 1 LAST WATTAGE 1/16W
J 0
(4165 -1375);
DISPLAY 0.638298 (4165 -1375);
FORCEPROP 1 LAST TOLERANCE 1%
J 0
(4170 -1325);
DISPLAY 0.638298 (4170 -1325);
FORCEPROP 1 LAST $LOCATION R4194
J 0
(4170 -1225);
DISPLAY 0.638298 (4170 -1225);
FORCEPROP 1 LASTPIN (4125 -1250) $PN 1
J 0
(4130 -1288);
DISPLAY 0.787234 (4130 -1288);
PAINT MONO (4130 -1288);
FORCEPROP 1 LASTPIN (4125 -1450) $PN 2
J 0
(4130 -1440);
DISPLAY 0.787234 (4130 -1440);
PAINT MONO (4130 -1440);
FORCEPROP 1 LAST PATH I128
J 0
(4175 -1175);
DISPLAY 0.978723 (4175 -1175);
PAINT WHITE (4175 -1175);
DISPLAY INVISIBLE (4175 -1175);
FORCEPROP 2 LAST CDS_LIB pure_quanta
J 0
(4125 -1350);
DISPLAY INVISIBLE (4125 -1350);
FORCEPROP 0 LAST CDS_LOCATION R4194
J 0
(4175 -1175);
DISPLAY 1.021277 (4175 -1175);
DISPLAY INVISIBLE (4175 -1175);
FORCEPROP 0 LAST $SEC 1
J 0
(4175 -1175);
DISPLAY 0.680851 (4175 -1175);
PAINT MONO (4175 -1175);
DISPLAY INVISIBLE (4175 -1175);
FORCEPROP 0 LAST CDS_SEC 1
J 0
(4175 -1175);
DISPLAY 1.021277 (4175 -1175);
DISPLAY INVISIBLE (4175 -1175);
FORCEADD Q_RES..2
(4375 -1350);
FORCEPROP 1 LAST PART_NUMBER CS21002FB06
J 0
(4415 -1525);
DISPLAY 0.638298 (4415 -1525);
DISPLAY INVISIBLE (4415 -1525);
FORCEPROP 1 LAST MATERIAL EMPTY
J 0
(4415 -1425);
DISPLAY 0.638298 (4415 -1425);
PAINT RED (4415 -1425);
FORCEPROP 1 LAST TOLERANCE 1%
J 0
(4420 -1325);
DISPLAY 0.638298 (4420 -1325);
FORCEPROP 1 LAST PACK_TYPE 0402LF
J 0
(4415 -1475);
DISPLAY 0.638298 (4415 -1475);
FORCEPROP 1 LAST VALUE 1K
J 0
(4420 -1275);
DISPLAY 0.638298 (4420 -1275);
FORCEPROP 1 LAST WATTAGE 1/16W
J 0
(4415 -1375);
DISPLAY 0.638298 (4415 -1375);
FORCEPROP 1 LAST $LOCATION R4202
J 0
(4420 -1225);
DISPLAY 0.638298 (4420 -1225);
FORCEPROP 1 LASTPIN (4375 -1250) $PN 1
J 0
(4380 -1288);
DISPLAY 0.787234 (4380 -1288);
PAINT MONO (4380 -1288);
FORCEPROP 1 LASTPIN (4375 -1450) $PN 2
J 0
(4380 -1440);
DISPLAY 0.787234 (4380 -1440);
PAINT MONO (4380 -1440);
FORCEPROP 1 LAST PATH I129
J 0
(4425 -1175);
DISPLAY 0.978723 (4425 -1175);
PAINT WHITE (4425 -1175);
DISPLAY INVISIBLE (4425 -1175);
FORCEPROP 2 LAST CDS_LIB pure_quanta
J 0
(4375 -1350);
DISPLAY INVISIBLE (4375 -1350);
FORCEPROP 0 LAST CDS_LOCATION R4202
J 0
(4425 -1175);
DISPLAY 1.021277 (4425 -1175);
DISPLAY INVISIBLE (4425 -1175);
FORCEPROP 0 LAST $SEC 1
J 0
(4425 -1175);
DISPLAY 0.680851 (4425 -1175);
PAINT MONO (4425 -1175);
DISPLAY INVISIBLE (4425 -1175);
FORCEPROP 0 LAST CDS_SEC 1
J 0
(4425 -1175);
DISPLAY 1.021277 (4425 -1175);
DISPLAY INVISIBLE (4425 -1175);
FORCEADD UNIVERSAL_POWER..1
(4375 -925);
FORCEPROP 3 LASTPIN (4375 -975) SIG_NAME P3V3_AUX\g
J 0
(4385 -965);
DISPLAY 0.659574 (4385 -965);
PAINT MONO (4385 -965);
DISPLAY INVISIBLE (4385 -965);
FORCEPROP 1 LAST HDL_POWER P3V3_AUX
J 1
(4375 -875);
DISPLAY 0.872340 (4375 -875);
PAINT GREEN (4375 -875);
FORCEPROP 1 LAST PATH I130
J 0
(4425 -900);
DISPLAY 0.872340 (4425 -900);
PAINT AQUA (4425 -900);
DISPLAY INVISIBLE (4425 -900);
FORCEPROP 2 LAST CDS_LIB logical_power
J 0
(4375 -925);
PAINT MONO (4375 -925);
DISPLAY INVISIBLE (4375 -925);
FORCEADD OFFPAGE..3
R 2
(-1025 -2975);
FORCEPROP 2 LAST $XR0 233 
J 0
(-1305 -2975);
DISPLAY 0.638298 (-1305 -2975);
PAINT MONO (-1305 -2975);
FORCEPROP 1 LAST COMMENT_BODY TRUE
J 2
(-975 -3075);
DISPLAY 0.872340 (-975 -3075);
PAINT GREEN (-975 -3075);
DISPLAY INVISIBLE (-975 -3075);
FORCEPROP 1 LAST OFFPAGE TRUE
J 2
(-1350 -3100);
DISPLAY 0.872340 (-1350 -3100);
DISPLAY INVISIBLE (-1350 -3100);
FORCEPROP 2 LAST CDS_LIB standard
J 0
(-1025 -2975);
DISPLAY INVISIBLE (-1025 -2975);
FORCEPROP 2 LAST PATH I132
J 0
(-1225 -2925);
DISPLAY 1.021277 (-1225 -2925);
DISPLAY INVISIBLE (-1225 -2925);
FORCEADD OFFPAGE..1
(-1025 -2825);
FORCEPROP 2 LAST $XR0 233 
J 0
(-1277 -2825);
DISPLAY 0.638298 (-1277 -2825);
PAINT MONO (-1277 -2825);
FORCEPROP 2 LAST CDS_LIB standard
J 0
(-1025 -2825);
DISPLAY INVISIBLE (-1025 -2825);
FORCEPROP 1 LAST COMMENT_BODY TRUE
J 0
(-900 -2925);
DISPLAY 0.872340 (-900 -2925);
PAINT GREEN (-900 -2925);
DISPLAY INVISIBLE (-900 -2925);
FORCEPROP 1 LAST OFFPAGE TRUE
J 0
(-700 -2950);
DISPLAY 0.872340 (-700 -2950);
PAINT GREEN (-700 -2950);
DISPLAY INVISIBLE (-700 -2950);
FORCEPROP 2 LAST PATH I133
J 0
(-1200 -2775);
DISPLAY 1.021277 (-1200 -2775);
DISPLAY INVISIBLE (-1200 -2775);
FORCEADD Q_RES..1
(225 -2975);
FORCEPROP 1 LAST PART_NUMBER CS03322FB03
J 0
(50 -2775);
DISPLAY 0.638298 (50 -2775);
DISPLAY INVISIBLE (50 -2775);
FORCEPROP 1 LAST MATERIAL CHIP
J 0
(-100 -2975);
DISPLAY 0.638298 (-100 -2975);
FORCEPROP 1 LAST PACK_TYPE 0402LF
J 0
(575 -2975);
DISPLAY 0.638298 (575 -2975);
FORCEPROP 1 LAST VALUE 33.2
J 2
(450 -2975);
DISPLAY 0.638298 (450 -2975);
FORCEPROP 1 LAST WATTAGE 1/16W
J 2
(-125 -2975);
DISPLAY 0.638298 (-125 -2975);
FORCEPROP 1 LAST TOLERANCE 1%
J 0
(475 -2975);
DISPLAY 0.638298 (475 -2975);
FORCEPROP 1 LAST $LOCATION R3553
J 0
(25 -2975);
DISPLAY 0.638298 (25 -2975);
FORCEPROP 1 LASTPIN (125 -2975) $PN 1
J 0
(137 -2963);
DISPLAY 0.787234 (137 -2963);
PAINT MONO (137 -2963);
FORCEPROP 1 LASTPIN (325 -2975) $PN 2
J 0
(287 -2963);
DISPLAY 0.787234 (287 -2963);
PAINT MONO (287 -2963);
FORCEPROP 2 LAST CDS_LIB pure_quanta
J 0
(225 -2975);
DISPLAY INVISIBLE (225 -2975);
FORCEPROP 1 LAST PATH I134
J 0
(175 -2825);
DISPLAY 0.978723 (175 -2825);
PAINT WHITE (175 -2825);
DISPLAY INVISIBLE (175 -2825);
FORCEPROP 0 LAST CDS_LOCATION R3553
J 0
(575 -2925);
DISPLAY 1.021277 (575 -2925);
DISPLAY INVISIBLE (575 -2925);
FORCEPROP 0 LAST $SEC 1
J 0
(575 -2925);
DISPLAY 0.680851 (575 -2925);
PAINT MONO (575 -2925);
DISPLAY INVISIBLE (575 -2925);
FORCEPROP 0 LAST CDS_SEC 1
J 0
(575 -2925);
DISPLAY 1.021277 (575 -2925);
DISPLAY INVISIBLE (575 -2925);
FORCEADD Q_RES..1
(225 -3125);
FORCEPROP 1 LAST PART_NUMBER CS00002JB13
J 0
(-50 -3250);
DISPLAY 0.723404 (-50 -3250);
PAINT WHITE (-50 -3250);
DISPLAY INVISIBLE (-50 -3250);
FORCEPROP 1 LAST MATERIAL CHIP
J 0
(400 -3125);
DISPLAY 0.574468 (400 -3125);
FORCEPROP 1 LAST PACK_TYPE 0402LF
J 0
(525 -3125);
DISPLAY 0.574468 (525 -3125);
FORCEPROP 1 LAST VALUE 0
J 2
(375 -3125);
DISPLAY 0.574468 (375 -3125);
FORCEPROP 1 LAST $LOCATION R4212
J 0
(25 -3125);
DISPLAY 0.638298 (25 -3125);
FORCEPROP 1 LASTPIN (125 -3125) $PN 1
J 0
(137 -3113);
DISPLAY 0.787234 (137 -3113);
PAINT MONO (137 -3113);
FORCEPROP 1 LASTPIN (325 -3125) $PN 2
J 0
(287 -3113);
DISPLAY 0.787234 (287 -3113);
PAINT MONO (287 -3113);
FORCEPROP 2 LAST CDS_LIB pure_quanta
J 0
(225 -3125);
DISPLAY INVISIBLE (225 -3125);
FORCEPROP 1 LAST WATTAGE 1/16W
J 2
(300 -3200);
DISPLAY 0.723404 (300 -3200);
PAINT SKYBLUE (300 -3200);
DISPLAY INVISIBLE (300 -3200);
FORCEPROP 1 LAST TOLERANCE 5%
J 0
(25 -3200);
DISPLAY 0.723404 (25 -3200);
PAINT SKYBLUE (25 -3200);
DISPLAY INVISIBLE (25 -3200);
FORCEPROP 1 LAST PATH I135
J 0
(175 -2975);
DISPLAY 0.978723 (175 -2975);
PAINT WHITE (175 -2975);
DISPLAY INVISIBLE (175 -2975);
FORCEPROP 0 LAST CDS_LOCATION R4212
J 0
(525 -3075);
DISPLAY 1.021277 (525 -3075);
DISPLAY INVISIBLE (525 -3075);
FORCEPROP 0 LAST $SEC 1
J 0
(525 -3075);
DISPLAY 0.680851 (525 -3075);
PAINT MONO (525 -3075);
DISPLAY INVISIBLE (525 -3075);
FORCEPROP 0 LAST CDS_SEC 1
J 0
(525 -3075);
DISPLAY 1.021277 (525 -3075);
DISPLAY INVISIBLE (525 -3075);
FORCEADD Q_RES..1
(225 -2825);
FORCEPROP 1 LAST PART_NUMBER CS03322FB03
J 0
(100 -2725);
DISPLAY 0.638298 (100 -2725);
DISPLAY INVISIBLE (100 -2725);
FORCEPROP 1 LAST VALUE 33.2
J 2
(450 -2825);
DISPLAY 0.638298 (450 -2825);
FORCEPROP 1 LAST PACK_TYPE 0402LF
J 0
(575 -2825);
DISPLAY 0.638298 (575 -2825);
FORCEPROP 1 LAST TOLERANCE 1%
J 0
(475 -2825);
DISPLAY 0.638298 (475 -2825);
FORCEPROP 1 LAST MATERIAL CHIP
J 0
(-100 -2825);
DISPLAY 0.638298 (-100 -2825);
FORCEPROP 1 LAST WATTAGE 1/16W
J 2
(-125 -2825);
DISPLAY 0.638298 (-125 -2825);
FORCEPROP 1 LAST $LOCATION R3554
J 0
(25 -2825);
DISPLAY 0.638298 (25 -2825);
FORCEPROP 1 LASTPIN (125 -2825) $PN 1
J 0
(137 -2813);
DISPLAY 0.787234 (137 -2813);
PAINT MONO (137 -2813);
FORCEPROP 1 LASTPIN (325 -2825) $PN 2
J 0
(287 -2813);
DISPLAY 0.787234 (287 -2813);
PAINT MONO (287 -2813);
FORCEPROP 2 LAST CDS_LIB pure_quanta
J 0
(225 -2825);
DISPLAY INVISIBLE (225 -2825);
FORCEPROP 1 LAST PATH I136
J 0
(175 -2675);
DISPLAY 0.978723 (175 -2675);
PAINT WHITE (175 -2675);
DISPLAY INVISIBLE (175 -2675);
FORCEPROP 0 LAST CDS_LOCATION R3554
J 0
(575 -2775);
DISPLAY 1.021277 (575 -2775);
DISPLAY INVISIBLE (575 -2775);
FORCEPROP 0 LAST $SEC 1
J 0
(575 -2775);
DISPLAY 0.680851 (575 -2775);
PAINT MONO (575 -2775);
DISPLAY INVISIBLE (575 -2775);
FORCEPROP 0 LAST CDS_SEC 1
J 0
(575 -2775);
DISPLAY 1.021277 (575 -2775);
DISPLAY INVISIBLE (575 -2775);
FORCEADD UNIVERSAL_GND..1
(1550 -3400);
FORCEPROP 3 LASTPIN (1550 -3350) SIG_NAME GND\g
J 0
(1560 -3340);
DISPLAY 0.659574 (1560 -3340);
PAINT MONO (1560 -3340);
DISPLAY INVISIBLE (1560 -3340);
FORCEPROP 2 LAST CDS_LIB logical_power
J 0
(1550 -3400);
DISPLAY INVISIBLE (1550 -3400);
FORCEPROP 1 LAST HDL_POWER GND
J 1
(1575 -3475);
DISPLAY 0.872340 (1575 -3475);
PAINT GREEN (1575 -3475);
DISPLAY INVISIBLE (1575 -3475);
FORCEPROP 1 LAST PATH I137
J 0
(1625 -3400);
DISPLAY 0.872340 (1625 -3400);
PAINT AQUA (1625 -3400);
DISPLAY INVISIBLE (1625 -3400);
FORCEADD UNIVERSAL_GND..1
(2475 -2700);
FORCEPROP 3 LASTPIN (2475 -2650) SIG_NAME GND\g
J 0
(2485 -2640);
DISPLAY 0.659574 (2485 -2640);
PAINT MONO (2485 -2640);
DISPLAY INVISIBLE (2485 -2640);
FORCEPROP 1 LAST PATH I138
J 0
(2550 -2700);
DISPLAY 0.872340 (2550 -2700);
PAINT AQUA (2550 -2700);
DISPLAY INVISIBLE (2550 -2700);
FORCEPROP 2 LAST CDS_LIB logical_power
J 0
(2475 -2700);
DISPLAY INVISIBLE (2475 -2700);
FORCEPROP 1 LAST HDL_POWER GND
J 1
(2500 -2775);
DISPLAY 0.872340 (2500 -2775);
PAINT GREEN (2500 -2775);
DISPLAY INVISIBLE (2500 -2775);
FORCEADD Q_CAP..1
R 2
(2475 -2475);
FORCEPROP 1 LAST PART_NUMBER CH4104K1B00
J 2
(2425 -2625);
DISPLAY 0.510638 (2425 -2625);
DISPLAY INVISIBLE (2425 -2625);
FORCEPROP 1 LAST VOLTAGE 25V
J 2
(2425 -2475);
DISPLAY 0.510638 (2425 -2475);
FORCEPROP 1 LAST MATERIAL X7R
J 2
(2425 -2575);
DISPLAY 0.510638 (2425 -2575);
FORCEPROP 1 LAST PACK_TYPE 0402
J 2
(2425 -2675);
DISPLAY 0.510638 (2425 -2675);
FORCEPROP 1 LAST TOLERANCE 10%
J 2
(2425 -2525);
DISPLAY 0.510638 (2425 -2525);
FORCEPROP 1 LAST VALUE 0.1UF
J 2
(2425 -2425);
DISPLAY 0.510638 (2425 -2425);
FORCEPROP 1 LAST $LOCATION C2274
J 2
(2425 -2375);
DISPLAY 0.978723 (2425 -2375);
FORCEPROP 1 LASTPIN (2475 -2375) $PN 1
J 2
(2465 -2395);
DISPLAY 0.787234 (2465 -2395);
PAINT MONO (2465 -2395);
FORCEPROP 1 LASTPIN (2475 -2575) $PN 2
J 2
(2465 -2595);
DISPLAY 0.787234 (2465 -2595);
PAINT MONO (2465 -2595);
FORCEPROP 1 LAST PATH I139
J 2
(2425 -2325);
DISPLAY 0.978723 (2425 -2325);
PAINT WHITE (2425 -2325);
DISPLAY INVISIBLE (2425 -2325);
FORCEPROP 2 LAST CDS_LIB pure_quanta
J 0
(2475 -2475);
DISPLAY INVISIBLE (2475 -2475);
FORCEPROP 0 LAST CDS_LOCATION C2274
J 0
(2425 -2325);
DISPLAY 1.021277 (2425 -2325);
DISPLAY INVISIBLE (2425 -2325);
FORCEPROP 0 LAST $SEC 1
J 0
(2425 -2325);
DISPLAY 0.680851 (2425 -2325);
PAINT MONO (2425 -2325);
DISPLAY INVISIBLE (2425 -2325);
FORCEPROP 0 LAST CDS_SEC 1
J 0
(2425 -2325);
DISPLAY 1.021277 (2425 -2325);
DISPLAY INVISIBLE (2425 -2325);
FORCEADD UNIVERSAL_GND..1
(3825 -3650);
FORCEPROP 3 LASTPIN (3825 -3600) SIG_NAME GND\g
J 0
(3835 -3590);
DISPLAY 0.659574 (3835 -3590);
PAINT MONO (3835 -3590);
DISPLAY INVISIBLE (3835 -3590);
FORCEPROP 1 LAST PATH I140
J 0
(3900 -3650);
DISPLAY 0.872340 (3900 -3650);
PAINT AQUA (3900 -3650);
DISPLAY INVISIBLE (3900 -3650);
FORCEPROP 2 LAST CDS_LIB logical_power
J 0
(3825 -3650);
PAINT MONO (3825 -3650);
DISPLAY INVISIBLE (3825 -3650);
FORCEPROP 1 LAST HDL_POWER GND
J 1
(3850 -3725);
DISPLAY 0.872340 (3850 -3725);
PAINT GREEN (3850 -3725);
DISPLAY INVISIBLE (3850 -3725);
FORCEADD Q_RES..2
(3825 -3425);
FORCEPROP 1 LAST PART_NUMBER CS21002FB06
J 0
(3865 -3600);
DISPLAY 0.638298 (3865 -3600);
DISPLAY INVISIBLE (3865 -3600);
FORCEPROP 1 LAST MATERIAL CHIP
J 0
(3865 -3500);
DISPLAY 0.638298 (3865 -3500);
FORCEPROP 1 LAST PACK_TYPE 0402LF
J 0
(3865 -3550);
DISPLAY 0.638298 (3865 -3550);
FORCEPROP 1 LAST VALUE 1K
J 0
(3870 -3350);
DISPLAY 0.638298 (3870 -3350);
FORCEPROP 1 LAST WATTAGE 1/16W
J 0
(3865 -3450);
DISPLAY 0.638298 (3865 -3450);
FORCEPROP 1 LAST TOLERANCE 1%
J 0
(3870 -3400);
DISPLAY 0.638298 (3870 -3400);
FORCEPROP 1 LAST $LOCATION R4185
J 0
(3870 -3300);
DISPLAY 0.638298 (3870 -3300);
FORCEPROP 1 LASTPIN (3825 -3325) $PN 1
J 0
(3830 -3363);
DISPLAY 0.787234 (3830 -3363);
PAINT MONO (3830 -3363);
FORCEPROP 1 LASTPIN (3825 -3525) $PN 2
J 0
(3830 -3515);
DISPLAY 0.787234 (3830 -3515);
PAINT MONO (3830 -3515);
FORCEPROP 1 LAST PATH I141
J 0
(3875 -3250);
DISPLAY 0.978723 (3875 -3250);
PAINT WHITE (3875 -3250);
DISPLAY INVISIBLE (3875 -3250);
FORCEPROP 2 LAST CDS_LIB pure_quanta
J 0
(3825 -3425);
DISPLAY INVISIBLE (3825 -3425);
FORCEPROP 0 LAST CDS_LOCATION R4185
J 0
(3875 -3250);
DISPLAY 1.021277 (3875 -3250);
DISPLAY INVISIBLE (3875 -3250);
FORCEPROP 0 LAST $SEC 1
J 0
(3875 -3250);
DISPLAY 0.680851 (3875 -3250);
PAINT MONO (3875 -3250);
DISPLAY INVISIBLE (3875 -3250);
FORCEPROP 0 LAST CDS_SEC 1
J 0
(3875 -3250);
DISPLAY 1.021277 (3875 -3250);
DISPLAY INVISIBLE (3875 -3250);
FORCEADD Q_RES..2
(3825 -2825);
FORCEPROP 1 LAST PART_NUMBER CS21002FB06
J 0
(3865 -3000);
DISPLAY 0.638298 (3865 -3000);
DISPLAY INVISIBLE (3865 -3000);
FORCEPROP 1 LAST WATTAGE 1/16W
J 0
(3865 -2850);
DISPLAY 0.638298 (3865 -2850);
FORCEPROP 1 LAST VALUE 1K
J 0
(3870 -2750);
DISPLAY 0.638298 (3870 -2750);
FORCEPROP 1 LAST TOLERANCE 1%
J 0
(3870 -2800);
DISPLAY 0.638298 (3870 -2800);
FORCEPROP 1 LAST PACK_TYPE 0402LF
J 0
(3865 -2950);
DISPLAY 0.638298 (3865 -2950);
FORCEPROP 1 LAST MATERIAL EMPTY
J 0
(3865 -2900);
DISPLAY 0.638298 (3865 -2900);
PAINT RED (3865 -2900);
FORCEPROP 1 LAST $LOCATION R4184
J 0
(3870 -2700);
DISPLAY 0.638298 (3870 -2700);
FORCEPROP 1 LASTPIN (3825 -2725) $PN 1
J 0
(3830 -2763);
DISPLAY 0.787234 (3830 -2763);
PAINT MONO (3830 -2763);
FORCEPROP 1 LASTPIN (3825 -2925) $PN 2
J 0
(3830 -2915);
DISPLAY 0.787234 (3830 -2915);
PAINT MONO (3830 -2915);
FORCEPROP 1 LAST PATH I142
J 0
(3875 -2650);
DISPLAY 0.978723 (3875 -2650);
PAINT WHITE (3875 -2650);
DISPLAY INVISIBLE (3875 -2650);
FORCEPROP 2 LAST CDS_LIB pure_quanta
J 0
(3825 -2825);
DISPLAY INVISIBLE (3825 -2825);
FORCEPROP 0 LAST CDS_LOCATION R4184
J 0
(3875 -2650);
DISPLAY 1.021277 (3875 -2650);
DISPLAY INVISIBLE (3875 -2650);
FORCEPROP 0 LAST $SEC 1
J 0
(3875 -2650);
DISPLAY 0.680851 (3875 -2650);
PAINT MONO (3875 -2650);
DISPLAY INVISIBLE (3875 -2650);
FORCEPROP 0 LAST CDS_SEC 1
J 0
(3875 -2650);
DISPLAY 1.021277 (3875 -2650);
DISPLAY INVISIBLE (3875 -2650);
FORCEADD UNIVERSAL_POWER..1
(2475 -2150);
FORCEPROP 3 LASTPIN (2475 -2200) SIG_NAME P3V3_AUX\g
J 0
(2485 -2190);
DISPLAY 0.659574 (2485 -2190);
PAINT MONO (2485 -2190);
DISPLAY INVISIBLE (2485 -2190);
FORCEPROP 1 LAST HDL_POWER P3V3_AUX
J 1
(2475 -2100);
DISPLAY 0.872340 (2475 -2100);
PAINT GREEN (2475 -2100);
FORCEPROP 1 LAST PATH I143
J 0
(2525 -2125);
DISPLAY 0.872340 (2525 -2125);
PAINT AQUA (2525 -2125);
DISPLAY INVISIBLE (2525 -2125);
FORCEPROP 2 LAST CDS_LIB logical_power
J 0
(2475 -2150);
DISPLAY INVISIBLE (2475 -2150);
FORCEADD UNIVERSAL_GND..1
(4075 -3650);
FORCEPROP 3 LASTPIN (4075 -3600) SIG_NAME GND\g
J 0
(4085 -3590);
DISPLAY 0.659574 (4085 -3590);
PAINT MONO (4085 -3590);
DISPLAY INVISIBLE (4085 -3590);
FORCEPROP 1 LAST PATH I144
J 0
(4150 -3650);
DISPLAY 0.872340 (4150 -3650);
PAINT AQUA (4150 -3650);
DISPLAY INVISIBLE (4150 -3650);
FORCEPROP 2 LAST CDS_LIB logical_power
J 0
(4075 -3650);
PAINT MONO (4075 -3650);
DISPLAY INVISIBLE (4075 -3650);
FORCEPROP 1 LAST HDL_POWER GND
J 1
(4100 -3725);
DISPLAY 0.872340 (4100 -3725);
PAINT GREEN (4100 -3725);
DISPLAY INVISIBLE (4100 -3725);
FORCEADD Q_RES..2
(4075 -3425);
FORCEPROP 1 LAST PART_NUMBER CS21002FB06
J 0
(4115 -3600);
DISPLAY 0.638298 (4115 -3600);
DISPLAY INVISIBLE (4115 -3600);
FORCEPROP 1 LAST MATERIAL CHIP
J 0
(4115 -3500);
DISPLAY 0.638298 (4115 -3500);
FORCEPROP 1 LAST PACK_TYPE 0402LF
J 0
(4115 -3550);
DISPLAY 0.638298 (4115 -3550);
FORCEPROP 1 LAST VALUE 1K
J 0
(4120 -3350);
DISPLAY 0.638298 (4120 -3350);
FORCEPROP 1 LAST WATTAGE 1/16W
J 0
(4115 -3450);
DISPLAY 0.638298 (4115 -3450);
FORCEPROP 1 LAST TOLERANCE 1%
J 0
(4120 -3400);
DISPLAY 0.638298 (4120 -3400);
FORCEPROP 1 LAST $LOCATION R4193
J 0
(4120 -3300);
DISPLAY 0.638298 (4120 -3300);
FORCEPROP 1 LASTPIN (4075 -3325) $PN 1
J 0
(4080 -3363);
DISPLAY 0.787234 (4080 -3363);
PAINT MONO (4080 -3363);
FORCEPROP 1 LASTPIN (4075 -3525) $PN 2
J 0
(4080 -3515);
DISPLAY 0.787234 (4080 -3515);
PAINT MONO (4080 -3515);
FORCEPROP 1 LAST PATH I145
J 0
(4125 -3250);
DISPLAY 0.978723 (4125 -3250);
PAINT WHITE (4125 -3250);
DISPLAY INVISIBLE (4125 -3250);
FORCEPROP 2 LAST CDS_LIB pure_quanta
J 0
(4075 -3425);
DISPLAY INVISIBLE (4075 -3425);
FORCEPROP 0 LAST CDS_LOCATION R4193
J 0
(4125 -3250);
DISPLAY 1.021277 (4125 -3250);
DISPLAY INVISIBLE (4125 -3250);
FORCEPROP 0 LAST $SEC 1
J 0
(4125 -3250);
DISPLAY 0.680851 (4125 -3250);
PAINT MONO (4125 -3250);
DISPLAY INVISIBLE (4125 -3250);
FORCEPROP 0 LAST CDS_SEC 1
J 0
(4125 -3250);
DISPLAY 1.021277 (4125 -3250);
DISPLAY INVISIBLE (4125 -3250);
FORCEADD UNIVERSAL_GND..1
(4325 -3650);
FORCEPROP 3 LASTPIN (4325 -3600) SIG_NAME GND\g
J 0
(4335 -3590);
DISPLAY 0.659574 (4335 -3590);
PAINT MONO (4335 -3590);
DISPLAY INVISIBLE (4335 -3590);
FORCEPROP 1 LAST PATH I146
J 0
(4400 -3650);
DISPLAY 0.872340 (4400 -3650);
PAINT AQUA (4400 -3650);
DISPLAY INVISIBLE (4400 -3650);
FORCEPROP 2 LAST CDS_LIB logical_power
J 0
(4325 -3650);
PAINT MONO (4325 -3650);
DISPLAY INVISIBLE (4325 -3650);
FORCEPROP 1 LAST HDL_POWER GND
J 1
(4350 -3725);
DISPLAY 0.872340 (4350 -3725);
PAINT GREEN (4350 -3725);
DISPLAY INVISIBLE (4350 -3725);
FORCEADD Q_RES..2
(4325 -3425);
FORCEPROP 1 LAST PART_NUMBER CS21002FB06
J 0
(4365 -3600);
DISPLAY 0.638298 (4365 -3600);
DISPLAY INVISIBLE (4365 -3600);
FORCEPROP 1 LAST MATERIAL CHIP
J 0
(4365 -3500);
DISPLAY 0.638298 (4365 -3500);
FORCEPROP 1 LAST PACK_TYPE 0402LF
J 0
(4365 -3550);
DISPLAY 0.638298 (4365 -3550);
FORCEPROP 1 LAST WATTAGE 1/16W
J 0
(4365 -3450);
DISPLAY 0.638298 (4365 -3450);
FORCEPROP 1 LAST VALUE 1K
J 0
(4370 -3350);
DISPLAY 0.638298 (4370 -3350);
FORCEPROP 1 LAST TOLERANCE 1%
J 0
(4370 -3400);
DISPLAY 0.638298 (4370 -3400);
FORCEPROP 1 LAST $LOCATION R4201
J 0
(4370 -3300);
DISPLAY 0.638298 (4370 -3300);
FORCEPROP 1 LASTPIN (4325 -3325) $PN 1
J 0
(4330 -3363);
DISPLAY 0.787234 (4330 -3363);
PAINT MONO (4330 -3363);
FORCEPROP 1 LASTPIN (4325 -3525) $PN 2
J 0
(4330 -3515);
DISPLAY 0.787234 (4330 -3515);
PAINT MONO (4330 -3515);
FORCEPROP 1 LAST PATH I147
J 0
(4375 -3250);
DISPLAY 0.978723 (4375 -3250);
PAINT WHITE (4375 -3250);
DISPLAY INVISIBLE (4375 -3250);
FORCEPROP 2 LAST CDS_LIB pure_quanta
J 0
(4325 -3425);
DISPLAY INVISIBLE (4325 -3425);
FORCEPROP 0 LAST CDS_LOCATION R4201
J 0
(4375 -3250);
DISPLAY 1.021277 (4375 -3250);
DISPLAY INVISIBLE (4375 -3250);
FORCEPROP 0 LAST $SEC 1
J 0
(4375 -3250);
DISPLAY 0.680851 (4375 -3250);
PAINT MONO (4375 -3250);
DISPLAY INVISIBLE (4375 -3250);
FORCEPROP 0 LAST CDS_SEC 1
J 0
(4375 -3250);
DISPLAY 1.021277 (4375 -3250);
DISPLAY INVISIBLE (4375 -3250);
FORCEADD Q_RES..2
(4075 -2825);
FORCEPROP 1 LAST PART_NUMBER CS21002FB06
J 0
(4115 -3000);
DISPLAY 0.638298 (4115 -3000);
DISPLAY INVISIBLE (4115 -3000);
FORCEPROP 1 LAST TOLERANCE 1%
J 0
(4120 -2800);
DISPLAY 0.638298 (4120 -2800);
FORCEPROP 1 LAST WATTAGE 1/16W
J 0
(4115 -2850);
DISPLAY 0.638298 (4115 -2850);
FORCEPROP 1 LAST VALUE 1K
J 0
(4120 -2750);
DISPLAY 0.638298 (4120 -2750);
FORCEPROP 1 LAST PACK_TYPE 0402LF
J 0
(4115 -2950);
DISPLAY 0.638298 (4115 -2950);
FORCEPROP 1 LAST MATERIAL EMPTY
J 0
(4115 -2900);
DISPLAY 0.638298 (4115 -2900);
PAINT RED (4115 -2900);
FORCEPROP 1 LAST $LOCATION R4192
J 0
(4120 -2700);
DISPLAY 0.638298 (4120 -2700);
FORCEPROP 1 LASTPIN (4075 -2725) $PN 1
J 0
(4080 -2763);
DISPLAY 0.787234 (4080 -2763);
PAINT MONO (4080 -2763);
FORCEPROP 1 LASTPIN (4075 -2925) $PN 2
J 0
(4080 -2915);
DISPLAY 0.787234 (4080 -2915);
PAINT MONO (4080 -2915);
FORCEPROP 1 LAST PATH I148
J 0
(4125 -2650);
DISPLAY 0.978723 (4125 -2650);
PAINT WHITE (4125 -2650);
DISPLAY INVISIBLE (4125 -2650);
FORCEPROP 2 LAST CDS_LIB pure_quanta
J 0
(4075 -2825);
DISPLAY INVISIBLE (4075 -2825);
FORCEPROP 0 LAST CDS_LOCATION R4192
J 0
(4125 -2650);
DISPLAY 1.021277 (4125 -2650);
DISPLAY INVISIBLE (4125 -2650);
FORCEPROP 0 LAST $SEC 1
J 0
(4125 -2650);
DISPLAY 0.680851 (4125 -2650);
PAINT MONO (4125 -2650);
DISPLAY INVISIBLE (4125 -2650);
FORCEPROP 0 LAST CDS_SEC 1
J 0
(4125 -2650);
DISPLAY 1.021277 (4125 -2650);
DISPLAY INVISIBLE (4125 -2650);
FORCEADD Q_RES..2
(4325 -2825);
FORCEPROP 1 LAST PART_NUMBER CS21002FB06
J 0
(4365 -3000);
DISPLAY 0.638298 (4365 -3000);
DISPLAY INVISIBLE (4365 -3000);
FORCEPROP 1 LAST WATTAGE 1/16W
J 0
(4365 -2850);
DISPLAY 0.638298 (4365 -2850);
FORCEPROP 1 LAST VALUE 1K
J 0
(4370 -2750);
DISPLAY 0.638298 (4370 -2750);
FORCEPROP 1 LAST PACK_TYPE 0402LF
J 0
(4365 -2950);
DISPLAY 0.638298 (4365 -2950);
FORCEPROP 1 LAST TOLERANCE 1%
J 0
(4370 -2800);
DISPLAY 0.638298 (4370 -2800);
FORCEPROP 1 LAST MATERIAL EMPTY
J 0
(4365 -2900);
DISPLAY 0.638298 (4365 -2900);
PAINT RED (4365 -2900);
FORCEPROP 1 LAST $LOCATION R4200
J 0
(4370 -2700);
DISPLAY 0.638298 (4370 -2700);
FORCEPROP 1 LASTPIN (4325 -2725) $PN 1
J 0
(4330 -2763);
DISPLAY 0.787234 (4330 -2763);
PAINT MONO (4330 -2763);
FORCEPROP 1 LASTPIN (4325 -2925) $PN 2
J 0
(4330 -2915);
DISPLAY 0.787234 (4330 -2915);
PAINT MONO (4330 -2915);
FORCEPROP 1 LAST PATH I149
J 0
(4375 -2650);
DISPLAY 0.978723 (4375 -2650);
PAINT WHITE (4375 -2650);
DISPLAY INVISIBLE (4375 -2650);
FORCEPROP 2 LAST CDS_LIB pure_quanta
J 0
(4325 -2825);
DISPLAY INVISIBLE (4325 -2825);
FORCEPROP 0 LAST CDS_LOCATION R4200
J 0
(4375 -2650);
DISPLAY 1.021277 (4375 -2650);
DISPLAY INVISIBLE (4375 -2650);
FORCEPROP 0 LAST $SEC 1
J 0
(4375 -2650);
DISPLAY 0.680851 (4375 -2650);
PAINT MONO (4375 -2650);
DISPLAY INVISIBLE (4375 -2650);
FORCEPROP 0 LAST CDS_SEC 1
J 0
(4375 -2650);
DISPLAY 1.021277 (4375 -2650);
DISPLAY INVISIBLE (4375 -2650);
FORCEADD UNIVERSAL_POWER..1
(2600 2275);
FORCEPROP 3 LASTPIN (2600 2225) SIG_NAME P3V3_AUX\g
J 0
(2610 2235);
DISPLAY 0.659574 (2610 2235);
PAINT MONO (2610 2235);
DISPLAY INVISIBLE (2610 2235);
FORCEPROP 1 LAST HDL_POWER P3V3_AUX
J 1
(2600 2325);
DISPLAY 0.872340 (2600 2325);
PAINT GREEN (2600 2325);
FORCEPROP 1 LAST PATH I15
J 0
(2650 2300);
DISPLAY 0.872340 (2650 2300);
PAINT AQUA (2650 2300);
DISPLAY INVISIBLE (2650 2300);
FORCEPROP 2 LAST CDS_LIB logical_power
J 0
(2600 2275);
DISPLAY INVISIBLE (2600 2275);
FORCEADD UNIVERSAL_POWER..1
(4325 -2400);
FORCEPROP 3 LASTPIN (4325 -2450) SIG_NAME P3V3_AUX\g
J 0
(4335 -2440);
DISPLAY 0.659574 (4335 -2440);
PAINT MONO (4335 -2440);
DISPLAY INVISIBLE (4335 -2440);
FORCEPROP 1 LAST HDL_POWER P3V3_AUX
J 1
(4325 -2350);
DISPLAY 0.872340 (4325 -2350);
PAINT GREEN (4325 -2350);
FORCEPROP 1 LAST PATH I150
J 0
(4375 -2375);
DISPLAY 0.872340 (4375 -2375);
PAINT AQUA (4375 -2375);
DISPLAY INVISIBLE (4375 -2375);
FORCEPROP 2 LAST CDS_LIB logical_power
J 0
(4325 -2400);
PAINT MONO (4325 -2400);
DISPLAY INVISIBLE (4325 -2400);
FORCEADD UNIVERSAL_POWER..1
(-200 2025);
FORCEPROP 3 LASTPIN (-200 1975) SIG_NAME P3V3_AUX\g
J 0
(-190 1985);
DISPLAY 0.659574 (-190 1985);
PAINT MONO (-190 1985);
DISPLAY INVISIBLE (-190 1985);
FORCEPROP 1 LAST HDL_POWER P3V3_AUX
J 1
(-200 2075);
DISPLAY 0.872340 (-200 2075);
PAINT GREEN (-200 2075);
FORCEPROP 1 LAST PATH I153
J 0
(-150 2050);
DISPLAY 0.872340 (-150 2050);
PAINT AQUA (-150 2050);
DISPLAY INVISIBLE (-150 2050);
FORCEPROP 2 LAST CDS_LIB logical_power
J 0
(-200 2025);
DISPLAY INVISIBLE (-200 2025);
FORCEADD UNIVERSAL_POWER..1
(-250 550);
FORCEPROP 3 LASTPIN (-250 500) SIG_NAME P3V3_AUX\g
J 0
(-240 510);
DISPLAY 0.659574 (-240 510);
PAINT MONO (-240 510);
DISPLAY INVISIBLE (-240 510);
FORCEPROP 1 LAST HDL_POWER P3V3_AUX
J 1
(-250 600);
DISPLAY 0.872340 (-250 600);
PAINT GREEN (-250 600);
FORCEPROP 2 LAST CDS_LIB logical_power
J 0
(-250 550);
DISPLAY INVISIBLE (-250 550);
FORCEPROP 1 LAST PATH I154
J 0
(-200 575);
DISPLAY 0.872340 (-200 575);
PAINT AQUA (-200 575);
DISPLAY INVISIBLE (-200 575);
FORCEADD UNIVERSAL_POWER..1
(-250 -925);
FORCEPROP 3 LASTPIN (-250 -975) SIG_NAME P3V3_AUX\g
J 0
(-240 -965);
DISPLAY 0.659574 (-240 -965);
PAINT MONO (-240 -965);
DISPLAY INVISIBLE (-240 -965);
FORCEPROP 1 LAST HDL_POWER P3V3_AUX
J 1
(-250 -875);
DISPLAY 0.872340 (-250 -875);
PAINT GREEN (-250 -875);
FORCEPROP 1 LAST PATH I156
J 0
(-200 -900);
DISPLAY 0.872340 (-200 -900);
PAINT AQUA (-200 -900);
DISPLAY INVISIBLE (-200 -900);
FORCEPROP 2 LAST CDS_LIB logical_power
J 0
(-250 -925);
DISPLAY INVISIBLE (-250 -925);
FORCEADD UNIVERSAL_POWER..1
(-350 -2350);
FORCEPROP 3 LASTPIN (-350 -2400) SIG_NAME P3V3_AUX\g
J 0
(-340 -2390);
DISPLAY 0.659574 (-340 -2390);
PAINT MONO (-340 -2390);
DISPLAY INVISIBLE (-340 -2390);
FORCEPROP 1 LAST HDL_POWER P3V3_AUX
J 1
(-350 -2300);
DISPLAY 0.872340 (-350 -2300);
PAINT GREEN (-350 -2300);
FORCEPROP 2 LAST CDS_LIB logical_power
J 0
(-350 -2350);
DISPLAY INVISIBLE (-350 -2350);
FORCEPROP 1 LAST PATH I159
J 0
(-300 -2325);
DISPLAY 0.872340 (-300 -2325);
PAINT AQUA (-300 -2325);
DISPLAY INVISIBLE (-300 -2325);
FORCEADD Q_CAP..1
R 2
(2600 1950);
FORCEPROP 1 LAST PART_NUMBER CH4104K1B00
J 2
(2550 1800);
DISPLAY 0.510638 (2550 1800);
DISPLAY INVISIBLE (2550 1800);
FORCEPROP 1 LAST PACK_TYPE 0402
J 2
(2550 1750);
DISPLAY 0.510638 (2550 1750);
FORCEPROP 1 LAST VALUE 0.1UF
J 2
(2550 2000);
DISPLAY 0.510638 (2550 2000);
FORCEPROP 1 LAST VOLTAGE 25V
J 2
(2550 1950);
DISPLAY 0.510638 (2550 1950);
FORCEPROP 1 LAST TOLERANCE 10%
J 2
(2550 1900);
DISPLAY 0.510638 (2550 1900);
FORCEPROP 1 LAST MATERIAL X7R
J 2
(2550 1850);
DISPLAY 0.510638 (2550 1850);
FORCEPROP 1 LAST $LOCATION C2010
J 2
(2550 2050);
DISPLAY 0.978723 (2550 2050);
FORCEPROP 1 LASTPIN (2600 2050) $PN 1
J 2
(2590 2030);
DISPLAY 0.787234 (2590 2030);
PAINT MONO (2590 2030);
FORCEPROP 1 LASTPIN (2600 1850) $PN 2
J 2
(2590 1830);
DISPLAY 0.787234 (2590 1830);
PAINT MONO (2590 1830);
FORCEPROP 2 LAST CDS_LIB pure_quanta
J 0
(2600 1950);
DISPLAY INVISIBLE (2600 1950);
FORCEPROP 1 LAST PATH I16
J 2
(2550 2100);
DISPLAY 0.978723 (2550 2100);
PAINT WHITE (2550 2100);
DISPLAY INVISIBLE (2550 2100);
FORCEPROP 0 LAST CDS_LOCATION C2010
J 0
(2550 2100);
DISPLAY 1.021277 (2550 2100);
DISPLAY INVISIBLE (2550 2100);
FORCEPROP 0 LAST $SEC 1
J 0
(2550 2100);
DISPLAY 0.680851 (2550 2100);
PAINT MONO (2550 2100);
DISPLAY INVISIBLE (2550 2100);
FORCEPROP 0 LAST CDS_SEC 1
J 0
(2550 2100);
DISPLAY 1.021277 (2550 2100);
DISPLAY INVISIBLE (2550 2100);
FORCEADD OFFPAGE..2
R 2
(-1050 -3125);
FORCEPROP 2 LAST $XR1 214 
J 0
(-1425 -3125);
DISPLAY 0.638298 (-1425 -3125);
PAINT MONO (-1425 -3125);
FORCEPROP 2 LAST $XR0 170 
J 0
(-1305 -3125);
DISPLAY 0.638298 (-1305 -3125);
PAINT MONO (-1305 -3125);
FORCEPROP 2 LAST CDS_LIB standard
J 2
(-1050 -3125);
DISPLAY INVISIBLE (-1050 -3125);
FORCEPROP 2 LAST PATH I160
J 2
(-1225 -3050);
DISPLAY 1.021277 (-1225 -3050);
DISPLAY INVISIBLE (-1225 -3050);
FORCEPROP 1 LAST COMMENT_BODY TRUE
J 2
(-1005 -3220);
DISPLAY 0.872340 (-1005 -3220);
PAINT GREEN (-1005 -3220);
DISPLAY INVISIBLE (-1005 -3220);
FORCEPROP 1 LAST OFFPAGE TRUE
J 2
(-1375 -3250);
DISPLAY 0.872340 (-1375 -3250);
PAINT AQUA (-1375 -3250);
DISPLAY INVISIBLE (-1375 -3250);
FORCEADD OFFPAGE..2
R 2
(-975 -1650);
FORCEPROP 2 LAST $XR1 214 
J 0
(-1350 -1650);
DISPLAY 0.638298 (-1350 -1650);
PAINT MONO (-1350 -1650);
FORCEPROP 2 LAST $XR0 170 
J 0
(-1230 -1650);
DISPLAY 0.638298 (-1230 -1650);
PAINT MONO (-1230 -1650);
FORCEPROP 2 LAST CDS_LIB standard
J 0
(-975 -1650);
DISPLAY INVISIBLE (-975 -1650);
FORCEPROP 2 LAST PATH I161
J 0
(-925 -1575);
DISPLAY 1.021277 (-925 -1575);
DISPLAY INVISIBLE (-925 -1575);
FORCEPROP 1 LAST OFFPAGE TRUE
J 2
(-1300 -1775);
DISPLAY 0.872340 (-1300 -1775);
PAINT AQUA (-1300 -1775);
DISPLAY INVISIBLE (-1300 -1775);
FORCEPROP 1 LAST COMMENT_BODY TRUE
J 2
(-930 -1745);
DISPLAY 0.872340 (-930 -1745);
PAINT GREEN (-930 -1745);
DISPLAY INVISIBLE (-930 -1745);
FORCEADD OFFPAGE..2
R 2
(-975 -175);
FORCEPROP 2 LAST $XR1 214 
J 0
(-1350 -175);
DISPLAY 0.638298 (-1350 -175);
PAINT MONO (-1350 -175);
FORCEPROP 2 LAST $XR0 170 
J 0
(-1230 -175);
DISPLAY 0.638298 (-1230 -175);
PAINT MONO (-1230 -175);
FORCEPROP 1 LAST OFFPAGE TRUE
J 2
(-1300 -300);
DISPLAY 0.872340 (-1300 -300);
PAINT AQUA (-1300 -300);
DISPLAY INVISIBLE (-1300 -300);
FORCEPROP 1 LAST COMMENT_BODY TRUE
J 2
(-930 -270);
DISPLAY 0.872340 (-930 -270);
PAINT GREEN (-930 -270);
DISPLAY INVISIBLE (-930 -270);
FORCEPROP 2 LAST PATH I162
J 0
(-925 -100);
DISPLAY 1.021277 (-925 -100);
DISPLAY INVISIBLE (-925 -100);
FORCEPROP 2 LAST CDS_LIB standard
J 0
(-975 -175);
DISPLAY INVISIBLE (-975 -175);
FORCEADD OFFPAGE..2
R 2
(-900 1300);
FORCEPROP 2 LAST $XR1 214 
J 0
(-1305 1300);
DISPLAY 0.638298 (-1305 1300);
PAINT MONO (-1305 1300);
FORCEPROP 2 LAST $XR0 170 
J 0
(-1185 1300);
DISPLAY 0.638298 (-1185 1300);
PAINT MONO (-1185 1300);
FORCEPROP 2 LAST CDS_LIB standard
J 0
(-900 1300);
DISPLAY INVISIBLE (-900 1300);
FORCEPROP 2 LAST PATH I163
J 0
(-850 1375);
DISPLAY 1.021277 (-850 1375);
DISPLAY INVISIBLE (-850 1375);
FORCEPROP 1 LAST COMMENT_BODY TRUE
J 2
(-855 1205);
DISPLAY 0.872340 (-855 1205);
PAINT GREEN (-855 1205);
DISPLAY INVISIBLE (-855 1205);
FORCEPROP 1 LAST OFFPAGE TRUE
J 2
(-1225 1175);
DISPLAY 0.872340 (-1225 1175);
PAINT AQUA (-1225 1175);
DISPLAY INVISIBLE (-1225 1175);
FORCEADD LM75BD..1
(2150 1375);
FORCEPROP 1 LAST PART_NUMBER AL0075BD000
J 0
(1931 1834);
DISPLAY 0.723404 (1931 1834);
PAINT GREEN (1931 1834);
DISPLAY INVISIBLE (1931 1834);
FORCEPROP 2 LAST PART_TYPE SMLF
J 0
(1950 2075);
DISPLAY 1.021277 (1950 2075);
FORCEPROP 1 LAST MATERIAL IC
J 0
(1931 1707);
DISPLAY 0.723404 (1931 1707);
PAINT GREEN (1931 1707);
FORCEPROP 2 LAST VALUE LM75BD
J 0
(1950 2025);
DISPLAY 1.021277 (1950 2025);
FORCEPROP 1 LAST LOCATION U270
J 0
(1931 1981);
DISPLAY 0.723404 (1931 1981);
PAINT GREEN (1931 1981);
FORCEPROP 0 LASTPIN (2525 1450) $PN 7
J 0
(2535 1460);
DISPLAY 0.680851 (2535 1460);
PAINT MONO (2535 1460);
FORCEPROP 0 LASTPIN (2525 1300) $PN 6
J 0
(2535 1310);
DISPLAY 0.680851 (2535 1310);
PAINT MONO (2535 1310);
FORCEPROP 0 LASTPIN (2525 1150) $PN 5
J 0
(2535 1160);
DISPLAY 0.680851 (2535 1160);
PAINT MONO (2535 1160);
FORCEPROP 0 LASTPIN (1775 1150) $PN 4
J 2
(1765 1160);
DISPLAY 0.680851 (1765 1160);
PAINT MONO (1765 1160);
FORCEPROP 0 LASTPIN (1775 1300) $PN 3
J 2
(1765 1310);
DISPLAY 0.680851 (1765 1310);
PAINT MONO (1765 1310);
FORCEPROP 0 LASTPIN (1775 1450) $PN 2
J 2
(1765 1460);
DISPLAY 0.680851 (1765 1460);
PAINT MONO (1765 1460);
FORCEPROP 0 LASTPIN (1775 1600) $PN 1
J 2
(1765 1610);
DISPLAY 0.680851 (1765 1610);
PAINT MONO (1765 1610);
FORCEPROP 0 LASTPIN (2525 1600) $PN 8
J 0
(2535 1610);
DISPLAY 0.680851 (2535 1610);
PAINT MONO (2535 1610);
FORCEPROP 2 LAST CDS_LIB pure_quanta
J 0
(2150 1375);
DISPLAY INVISIBLE (2150 1375);
FORCEPROP 1 LAST CDS_LMAN_SYM_OUTLINE -225,325,225,-325
J 0
(2150 1375);
DISPLAY 0.468085 (2150 1375);
PAINT GREEN (2150 1375);
DISPLAY INVISIBLE (2150 1375);
FORCEPROP 1 LAST PATH I164
J 0
(2150 1375);
DISPLAY 0.723404 (2150 1375);
PAINT GREEN (2150 1375);
DISPLAY INVISIBLE (2150 1375);
FORCEPROP 1 LAST NEEDS_NO_SIZE TRUE
J 0
(2150 1375);
DISPLAY 0.723404 (2150 1375);
PAINT GREEN (2150 1375);
DISPLAY INVISIBLE (2150 1375);
FORCEPROP 0 LAST $SEC 1
J 0
(1950 2125);
DISPLAY 0.680851 (1950 2125);
PAINT MONO (1950 2125);
DISPLAY INVISIBLE (1950 2125);
FORCEPROP 0 LAST CDS_SEC 1
J 0
(1950 2125);
DISPLAY 1.021277 (1950 2125);
DISPLAY INVISIBLE (1950 2125);
FORCEADD LM75BD..1
(2100 -100);
FORCEPROP 1 LAST PART_NUMBER AL0075BD000
J 0
(1881 359);
DISPLAY 0.723404 (1881 359);
PAINT GREEN (1881 359);
DISPLAY INVISIBLE (1881 359);
FORCEPROP 2 LAST PART_TYPE SMLF
J 0
(1900 600);
DISPLAY 1.021277 (1900 600);
FORCEPROP 1 LAST MATERIAL IC
J 0
(1881 232);
DISPLAY 0.723404 (1881 232);
PAINT GREEN (1881 232);
FORCEPROP 2 LAST VALUE LM75BD
J 0
(1900 550);
DISPLAY 1.021277 (1900 550);
FORCEPROP 1 LAST LOCATION U271
J 0
(1881 506);
DISPLAY 0.723404 (1881 506);
PAINT GREEN (1881 506);
FORCEPROP 0 LASTPIN (2475 -25) $PN 7
J 0
(2485 -15);
DISPLAY 0.680851 (2485 -15);
PAINT MONO (2485 -15);
FORCEPROP 0 LASTPIN (2475 -175) $PN 6
J 0
(2485 -165);
DISPLAY 0.680851 (2485 -165);
PAINT MONO (2485 -165);
FORCEPROP 0 LASTPIN (2475 -325) $PN 5
J 0
(2485 -315);
DISPLAY 0.680851 (2485 -315);
PAINT MONO (2485 -315);
FORCEPROP 0 LASTPIN (1725 -325) $PN 4
J 2
(1715 -315);
DISPLAY 0.680851 (1715 -315);
PAINT MONO (1715 -315);
FORCEPROP 0 LASTPIN (1725 -175) $PN 3
J 2
(1715 -165);
DISPLAY 0.680851 (1715 -165);
PAINT MONO (1715 -165);
FORCEPROP 0 LASTPIN (1725 -25) $PN 2
J 2
(1715 -15);
DISPLAY 0.680851 (1715 -15);
PAINT MONO (1715 -15);
FORCEPROP 0 LASTPIN (1725 125) $PN 1
J 2
(1715 135);
DISPLAY 0.680851 (1715 135);
PAINT MONO (1715 135);
FORCEPROP 0 LASTPIN (2475 125) $PN 8
J 0
(2485 135);
DISPLAY 0.680851 (2485 135);
PAINT MONO (2485 135);
FORCEPROP 1 LAST CDS_LMAN_SYM_OUTLINE -225,325,225,-325
J 0
(2100 -100);
DISPLAY 0.468085 (2100 -100);
PAINT GREEN (2100 -100);
DISPLAY INVISIBLE (2100 -100);
FORCEPROP 2 LAST CDS_LIB pure_quanta
J 0
(2100 -100);
DISPLAY INVISIBLE (2100 -100);
FORCEPROP 1 LAST PATH I165
J 0
(2100 -100);
DISPLAY 0.723404 (2100 -100);
PAINT GREEN (2100 -100);
DISPLAY INVISIBLE (2100 -100);
FORCEPROP 1 LAST NEEDS_NO_SIZE TRUE
J 0
(2100 -100);
DISPLAY 0.723404 (2100 -100);
PAINT GREEN (2100 -100);
DISPLAY INVISIBLE (2100 -100);
FORCEPROP 0 LAST $SEC 1
J 0
(1900 650);
DISPLAY 0.680851 (1900 650);
PAINT MONO (1900 650);
DISPLAY INVISIBLE (1900 650);
FORCEPROP 0 LAST CDS_SEC 1
J 0
(1900 650);
DISPLAY 1.021277 (1900 650);
DISPLAY INVISIBLE (1900 650);
FORCEADD LM75BD..1
(2075 -1575);
FORCEPROP 1 LAST PART_NUMBER AL0075BD000
J 0
(1856 -1116);
DISPLAY 0.723404 (1856 -1116);
PAINT GREEN (1856 -1116);
DISPLAY INVISIBLE (1856 -1116);
FORCEPROP 2 LAST VALUE LM75BD
J 0
(1875 -925);
DISPLAY 1.021277 (1875 -925);
FORCEPROP 1 LAST MATERIAL IC
J 0
(1856 -1243);
DISPLAY 0.723404 (1856 -1243);
PAINT GREEN (1856 -1243);
FORCEPROP 2 LAST PART_TYPE SMLF
J 0
(1875 -875);
DISPLAY 1.021277 (1875 -875);
FORCEPROP 1 LAST LOCATION U272
J 0
(1856 -969);
DISPLAY 0.723404 (1856 -969);
PAINT GREEN (1856 -969);
FORCEPROP 0 LASTPIN (2450 -1500) $PN 7
J 0
(2460 -1490);
DISPLAY 0.680851 (2460 -1490);
PAINT MONO (2460 -1490);
FORCEPROP 0 LASTPIN (2450 -1650) $PN 6
J 0
(2460 -1640);
DISPLAY 0.680851 (2460 -1640);
PAINT MONO (2460 -1640);
FORCEPROP 0 LASTPIN (2450 -1800) $PN 5
J 0
(2460 -1790);
DISPLAY 0.680851 (2460 -1790);
PAINT MONO (2460 -1790);
FORCEPROP 0 LASTPIN (1700 -1800) $PN 4
J 2
(1690 -1790);
DISPLAY 0.680851 (1690 -1790);
PAINT MONO (1690 -1790);
FORCEPROP 0 LASTPIN (1700 -1650) $PN 3
J 2
(1690 -1640);
DISPLAY 0.680851 (1690 -1640);
PAINT MONO (1690 -1640);
FORCEPROP 0 LASTPIN (1700 -1500) $PN 2
J 2
(1690 -1490);
DISPLAY 0.680851 (1690 -1490);
PAINT MONO (1690 -1490);
FORCEPROP 0 LASTPIN (1700 -1350) $PN 1
J 2
(1690 -1340);
DISPLAY 0.680851 (1690 -1340);
PAINT MONO (1690 -1340);
FORCEPROP 0 LASTPIN (2450 -1350) $PN 8
J 0
(2460 -1340);
DISPLAY 0.680851 (2460 -1340);
PAINT MONO (2460 -1340);
FORCEPROP 2 LAST CDS_LIB pure_quanta
J 0
(2075 -1575);
DISPLAY INVISIBLE (2075 -1575);
FORCEPROP 1 LAST CDS_LMAN_SYM_OUTLINE -225,325,225,-325
J 0
(2075 -1575);
DISPLAY 0.468085 (2075 -1575);
PAINT GREEN (2075 -1575);
DISPLAY INVISIBLE (2075 -1575);
FORCEPROP 1 LAST PATH I166
J 0
(2075 -1575);
DISPLAY 0.723404 (2075 -1575);
PAINT GREEN (2075 -1575);
DISPLAY INVISIBLE (2075 -1575);
FORCEPROP 1 LAST NEEDS_NO_SIZE TRUE
J 0
(2075 -1575);
DISPLAY 0.723404 (2075 -1575);
PAINT GREEN (2075 -1575);
DISPLAY INVISIBLE (2075 -1575);
FORCEPROP 0 LAST $SEC 1
J 0
(1875 -825);
DISPLAY 0.680851 (1875 -825);
PAINT MONO (1875 -825);
DISPLAY INVISIBLE (1875 -825);
FORCEPROP 0 LAST CDS_SEC 1
J 0
(1875 -825);
DISPLAY 1.021277 (1875 -825);
DISPLAY INVISIBLE (1875 -825);
FORCEADD LM75BD..1
(2025 -3050);
FORCEPROP 1 LAST PART_NUMBER AL0075BD000
J 0
(1806 -2591);
DISPLAY 0.723404 (1806 -2591);
PAINT GREEN (1806 -2591);
DISPLAY INVISIBLE (1806 -2591);
FORCEPROP 2 LAST PART_TYPE SMLF
J 0
(1825 -2350);
DISPLAY 1.021277 (1825 -2350);
FORCEPROP 2 LAST VALUE LM75BD
J 0
(1825 -2400);
DISPLAY 1.021277 (1825 -2400);
FORCEPROP 1 LAST MATERIAL IC
J 0
(1806 -2718);
DISPLAY 0.723404 (1806 -2718);
PAINT GREEN (1806 -2718);
FORCEPROP 1 LAST LOCATION U273
J 0
(1806 -2444);
DISPLAY 0.723404 (1806 -2444);
PAINT GREEN (1806 -2444);
FORCEPROP 0 LASTPIN (2400 -2975) $PN 7
J 0
(2410 -2965);
DISPLAY 0.680851 (2410 -2965);
PAINT MONO (2410 -2965);
FORCEPROP 0 LASTPIN (2400 -3125) $PN 6
J 0
(2410 -3115);
DISPLAY 0.680851 (2410 -3115);
PAINT MONO (2410 -3115);
FORCEPROP 0 LASTPIN (2400 -3275) $PN 5
J 0
(2410 -3265);
DISPLAY 0.680851 (2410 -3265);
PAINT MONO (2410 -3265);
FORCEPROP 0 LASTPIN (1650 -3275) $PN 4
J 2
(1640 -3265);
DISPLAY 0.680851 (1640 -3265);
PAINT MONO (1640 -3265);
FORCEPROP 0 LASTPIN (1650 -3125) $PN 3
J 2
(1640 -3115);
DISPLAY 0.680851 (1640 -3115);
PAINT MONO (1640 -3115);
FORCEPROP 0 LASTPIN (1650 -2975) $PN 2
J 2
(1640 -2965);
DISPLAY 0.680851 (1640 -2965);
PAINT MONO (1640 -2965);
FORCEPROP 0 LASTPIN (1650 -2825) $PN 1
J 2
(1640 -2815);
DISPLAY 0.680851 (1640 -2815);
PAINT MONO (1640 -2815);
FORCEPROP 0 LASTPIN (2400 -2825) $PN 8
J 0
(2410 -2815);
DISPLAY 0.680851 (2410 -2815);
PAINT MONO (2410 -2815);
FORCEPROP 1 LAST NEEDS_NO_SIZE TRUE
J 0
(2025 -3050);
DISPLAY 0.723404 (2025 -3050);
PAINT GREEN (2025 -3050);
DISPLAY INVISIBLE (2025 -3050);
FORCEPROP 1 LAST CDS_LMAN_SYM_OUTLINE -225,325,225,-325
J 0
(2025 -3050);
DISPLAY 0.468085 (2025 -3050);
PAINT GREEN (2025 -3050);
DISPLAY INVISIBLE (2025 -3050);
FORCEPROP 1 LAST PATH I167
J 0
(2025 -3050);
DISPLAY 0.723404 (2025 -3050);
PAINT GREEN (2025 -3050);
DISPLAY INVISIBLE (2025 -3050);
FORCEPROP 2 LAST CDS_LIB pure_quanta
J 0
(2025 -3050);
DISPLAY INVISIBLE (2025 -3050);
FORCEPROP 0 LAST $SEC 1
J 0
(1825 -2300);
DISPLAY 0.680851 (1825 -2300);
PAINT MONO (1825 -2300);
DISPLAY INVISIBLE (1825 -2300);
FORCEPROP 0 LAST CDS_SEC 1
J 0
(1825 -2300);
DISPLAY 1.021277 (1825 -2300);
DISPLAY INVISIBLE (1825 -2300);
FORCEADD Q_RES..2
(-200 1800);
FORCEPROP 1 LAST PART_NUMBER CS42002FB05
J 0
(-150 1700);
DISPLAY 0.510638 (-150 1700);
DISPLAY INVISIBLE (-150 1700);
FORCEPROP 1 LAST VALUE 200K
J 0
(-150 1900);
DISPLAY 0.510638 (-150 1900);
FORCEPROP 1 LAST PACK_TYPE 0402LF
J 0
(-150 1650);
DISPLAY 0.510638 (-150 1650);
FORCEPROP 1 LAST MATERIAL CHIP
J 0
(-150 1750);
DISPLAY 0.510638 (-150 1750);
FORCEPROP 1 LAST WATTAGE 1/16W
J 0
(-150 1800);
DISPLAY 0.510638 (-150 1800);
FORCEPROP 1 LAST TOLERANCE 1%
J 0
(-150 1850);
DISPLAY 0.510638 (-150 1850);
FORCEPROP 1 LAST LOCATION R4211
J 0
(-150 1950);
DISPLAY 0.638298 (-150 1950);
FORCEPROP 1 LASTPIN (-200 1900) $PN 1
J 0
(-195 1862);
DISPLAY 0.787234 (-195 1862);
PAINT MONO (-195 1862);
FORCEPROP 1 LASTPIN (-200 1700) $PN 2
J 0
(-195 1710);
DISPLAY 0.787234 (-195 1710);
PAINT MONO (-195 1710);
FORCEPROP 2 LAST CDS_LIB pure_quanta
J 0
(-200 1800);
DISPLAY INVISIBLE (-200 1800);
FORCEPROP 1 LAST PATH I168
J 0
(-150 1975);
DISPLAY 0.978723 (-150 1975);
PAINT WHITE (-150 1975);
DISPLAY INVISIBLE (-150 1975);
FORCEPROP 0 LAST $SEC 1
J 0
(-150 2000);
DISPLAY 0.680851 (-150 2000);
PAINT MONO (-150 2000);
DISPLAY INVISIBLE (-150 2000);
FORCEPROP 0 LAST CDS_SEC 1
J 0
(-150 2000);
DISPLAY 1.021277 (-150 2000);
DISPLAY INVISIBLE (-150 2000);
FORCEADD Q_RES..2
(-250 325);
FORCEPROP 1 LAST PART_NUMBER CS42002FB05
J 0
(-200 250);
DISPLAY 0.319149 (-200 250);
DISPLAY INVISIBLE (-200 250);
FORCEPROP 1 LAST MATERIAL EMPTY
J 0
(-200 300);
DISPLAY 0.319149 (-200 300);
PAINT RED (-200 300);
FORCEPROP 1 LAST WATTAGE 1/16W
J 0
(-200 350);
DISPLAY 0.319149 (-200 350);
FORCEPROP 1 LAST PACK_TYPE 0402LF
J 0
(-200 200);
DISPLAY 0.319149 (-200 200);
FORCEPROP 1 LAST TOLERANCE 1%
J 0
(-200 375);
DISPLAY 0.510638 (-200 375);
FORCEPROP 1 LAST VALUE 200K
J 0
(-200 450);
DISPLAY 0.319149 (-200 450);
FORCEPROP 1 LAST LOCATION R4209
J 0
(-200 475);
DISPLAY 0.404255 (-200 475);
FORCEPROP 1 LASTPIN (-250 425) $PN 1
J 0
(-245 387);
DISPLAY 0.787234 (-245 387);
PAINT MONO (-245 387);
FORCEPROP 1 LASTPIN (-250 225) $PN 2
J 0
(-245 235);
DISPLAY 0.787234 (-245 235);
PAINT MONO (-245 235);
FORCEPROP 2 LAST CDS_LIB pure_quanta
J 0
(-250 325);
DISPLAY INVISIBLE (-250 325);
FORCEPROP 1 LAST PATH I169
J 0
(-200 500);
DISPLAY 0.978723 (-200 500);
PAINT WHITE (-200 500);
DISPLAY INVISIBLE (-200 500);
FORCEPROP 0 LAST $SEC 1
J 0
(-200 500);
DISPLAY 0.680851 (-200 500);
PAINT MONO (-200 500);
DISPLAY INVISIBLE (-200 500);
FORCEPROP 0 LAST CDS_SEC 1
J 0
(-200 500);
DISPLAY 1.021277 (-200 500);
DISPLAY INVISIBLE (-200 500);
FORCEADD UNIVERSAL_GND..1
(2600 1725);
FORCEPROP 3 LASTPIN (2600 1775) SIG_NAME GND\g
J 0
(2610 1785);
DISPLAY 0.659574 (2610 1785);
PAINT MONO (2610 1785);
DISPLAY INVISIBLE (2610 1785);
FORCEPROP 2 LAST CDS_LIB logical_power
J 0
(2600 1725);
DISPLAY INVISIBLE (2600 1725);
FORCEPROP 1 LAST HDL_POWER GND
J 1
(2625 1650);
DISPLAY 0.872340 (2625 1650);
PAINT GREEN (2625 1650);
DISPLAY INVISIBLE (2625 1650);
FORCEPROP 1 LAST PATH I17
J 0
(2675 1725);
DISPLAY 0.872340 (2675 1725);
PAINT AQUA (2675 1725);
DISPLAY INVISIBLE (2675 1725);
FORCEADD Q_RES..2
(-250 -1175);
FORCEPROP 1 LAST PART_NUMBER CS42002FB05
J 0
(-200 -1250);
DISPLAY 0.319149 (-200 -1250);
DISPLAY INVISIBLE (-200 -1250);
FORCEPROP 1 LAST VALUE 200K
J 0
(-200 -1075);
DISPLAY 0.319149 (-200 -1075);
FORCEPROP 1 LAST TOLERANCE 1%
J 0
(-200 -1125);
DISPLAY 0.510638 (-200 -1125);
FORCEPROP 1 LAST PACK_TYPE 0402LF
J 0
(-200 -1300);
DISPLAY 0.319149 (-200 -1300);
FORCEPROP 1 LAST WATTAGE 1/16W
J 0
(-200 -1150);
DISPLAY 0.319149 (-200 -1150);
FORCEPROP 1 LAST MATERIAL EMPTY
J 0
(-200 -1200);
DISPLAY 0.319149 (-200 -1200);
PAINT RED (-200 -1200);
FORCEPROP 1 LAST LOCATION R4210
J 0
(-200 -1050);
DISPLAY 0.510638 (-200 -1050);
FORCEPROP 1 LASTPIN (-250 -1075) $PN 1
J 0
(-245 -1113);
DISPLAY 0.787234 (-245 -1113);
PAINT MONO (-245 -1113);
FORCEPROP 1 LASTPIN (-250 -1275) $PN 2
J 0
(-245 -1265);
DISPLAY 0.787234 (-245 -1265);
PAINT MONO (-245 -1265);
FORCEPROP 1 LAST PATH I170
J 0
(-200 -1000);
DISPLAY 0.978723 (-200 -1000);
PAINT WHITE (-200 -1000);
DISPLAY INVISIBLE (-200 -1000);
FORCEPROP 2 LAST CDS_LIB pure_quanta
J 0
(-250 -1175);
DISPLAY INVISIBLE (-250 -1175);
FORCEPROP 0 LAST $SEC 1
J 0
(-200 -1025);
DISPLAY 0.680851 (-200 -1025);
PAINT MONO (-200 -1025);
DISPLAY INVISIBLE (-200 -1025);
FORCEPROP 0 LAST CDS_SEC 1
J 0
(-200 -1025);
DISPLAY 1.021277 (-200 -1025);
DISPLAY INVISIBLE (-200 -1025);
FORCEADD Q_RES..2
(-350 -2625);
FORCEPROP 1 LAST PART_NUMBER CS42002FB05
J 0
(-300 -2700);
DISPLAY 0.319149 (-300 -2700);
DISPLAY INVISIBLE (-300 -2700);
FORCEPROP 1 LAST PACK_TYPE 0402LF
J 0
(-300 -2750);
DISPLAY 0.319149 (-300 -2750);
FORCEPROP 1 LAST MATERIAL EMPTY
J 0
(-300 -2650);
DISPLAY 0.319149 (-300 -2650);
PAINT RED (-300 -2650);
FORCEPROP 1 LAST WATTAGE 1/16W
J 0
(-300 -2600);
DISPLAY 0.319149 (-300 -2600);
FORCEPROP 1 LAST TOLERANCE 1%
J 0
(-300 -2575);
DISPLAY 0.510638 (-300 -2575);
FORCEPROP 1 LAST VALUE 200K
J 0
(-300 -2525);
DISPLAY 0.319149 (-300 -2525);
FORCEPROP 1 LAST LOCATION R4208
J 0
(-300 -2500);
DISPLAY 0.510638 (-300 -2500);
FORCEPROP 1 LASTPIN (-350 -2525) $PN 1
J 0
(-345 -2563);
DISPLAY 0.787234 (-345 -2563);
PAINT MONO (-345 -2563);
FORCEPROP 1 LASTPIN (-350 -2725) $PN 2
J 0
(-345 -2715);
DISPLAY 0.787234 (-345 -2715);
PAINT MONO (-345 -2715);
FORCEPROP 2 LAST CDS_LIB pure_quanta
J 0
(-350 -2625);
DISPLAY INVISIBLE (-350 -2625);
FORCEPROP 1 LAST PATH I171
J 0
(-300 -2450);
DISPLAY 0.978723 (-300 -2450);
PAINT WHITE (-300 -2450);
DISPLAY INVISIBLE (-300 -2450);
FORCEPROP 0 LAST $SEC 1
J 0
(-300 -2475);
DISPLAY 0.680851 (-300 -2475);
PAINT MONO (-300 -2475);
DISPLAY INVISIBLE (-300 -2475);
FORCEPROP 0 LAST CDS_SEC 1
J 0
(-300 -2475);
DISPLAY 1.021277 (-300 -2475);
DISPLAY INVISIBLE (-300 -2475);
FORCEADD UNIVERSAL_GND..1
(1675 1025);
FORCEPROP 3 LASTPIN (1675 1075) SIG_NAME GND\g
J 0
(1685 1085);
DISPLAY 0.659574 (1685 1085);
PAINT MONO (1685 1085);
DISPLAY INVISIBLE (1685 1085);
FORCEPROP 1 LAST PATH I21
J 0
(1750 1025);
DISPLAY 0.872340 (1750 1025);
PAINT AQUA (1750 1025);
DISPLAY INVISIBLE (1750 1025);
FORCEPROP 2 LAST CDS_LIB logical_power
J 0
(1675 1025);
DISPLAY INVISIBLE (1675 1025);
FORCEPROP 1 LAST HDL_POWER GND
J 1
(1700 950);
DISPLAY 0.872340 (1700 950);
PAINT GREEN (1700 950);
DISPLAY INVISIBLE (1700 950);
FORCEADD OFFPAGE..1
(-900 1600);
FORCEPROP 2 LAST $XR2 305 
J 0
(-1392 1600);
DISPLAY 0.638298 (-1392 1600);
PAINT MONO (-1392 1600);
FORCEPROP 2 LAST $XR1 251 
J 0
(-1272 1600);
DISPLAY 0.638298 (-1272 1600);
PAINT MONO (-1272 1600);
FORCEPROP 2 LAST $XR0 233 
J 0
(-1152 1600);
DISPLAY 0.638298 (-1152 1600);
PAINT MONO (-1152 1600);
FORCEPROP 2 LAST PATH I75
J 2
(-1100 1650);
DISPLAY 1.021277 (-1100 1650);
DISPLAY INVISIBLE (-1100 1650);
FORCEPROP 2 LAST CDS_LIB standard
J 0
(-900 1600);
DISPLAY INVISIBLE (-900 1600);
FORCEPROP 1 LAST COMMENT_BODY TRUE
J 0
(-775 1500);
DISPLAY 0.872340 (-775 1500);
PAINT GREEN (-775 1500);
DISPLAY INVISIBLE (-775 1500);
FORCEPROP 1 LAST OFFPAGE TRUE
J 0
(-575 1475);
DISPLAY 0.872340 (-575 1475);
PAINT GREEN (-575 1475);
DISPLAY INVISIBLE (-575 1475);
FORCEADD OFFPAGE..3
R 2
(-900 1450);
FORCEPROP 2 LAST $XR2 305 
J 0
(-1420 1450);
DISPLAY 0.638298 (-1420 1450);
PAINT MONO (-1420 1450);
FORCEPROP 2 LAST $XR1 251 
J 0
(-1300 1450);
DISPLAY 0.638298 (-1300 1450);
PAINT MONO (-1300 1450);
FORCEPROP 2 LAST $XR0 233 
J 0
(-1180 1450);
DISPLAY 0.638298 (-1180 1450);
PAINT MONO (-1180 1450);
FORCEPROP 2 LAST PATH I76
J 2
(-1125 1500);
DISPLAY 1.021277 (-1125 1500);
DISPLAY INVISIBLE (-1125 1500);
FORCEPROP 1 LAST COMMENT_BODY TRUE
J 2
(-850 1350);
DISPLAY 0.872340 (-850 1350);
PAINT GREEN (-850 1350);
DISPLAY INVISIBLE (-850 1350);
FORCEPROP 1 LAST OFFPAGE TRUE
J 2
(-1225 1325);
DISPLAY 0.872340 (-1225 1325);
DISPLAY INVISIBLE (-1225 1325);
FORCEPROP 2 LAST CDS_LIB standard
J 0
(-900 1450);
DISPLAY INVISIBLE (-900 1450);
FORCEADD Q_RES..1
(350 1450);
FORCEPROP 1 LAST PART_NUMBER CS03322FB03
J 0
(175 1650);
DISPLAY 0.638298 (175 1650);
DISPLAY INVISIBLE (175 1650);
FORCEPROP 1 LAST VALUE 33.2
J 2
(575 1450);
DISPLAY 0.638298 (575 1450);
FORCEPROP 1 LAST MATERIAL CHIP
J 0
(25 1450);
DISPLAY 0.638298 (25 1450);
FORCEPROP 1 LAST WATTAGE 1/16W
J 2
(0 1450);
DISPLAY 0.638298 (0 1450);
FORCEPROP 1 LAST TOLERANCE 1%
J 0
(600 1450);
DISPLAY 0.638298 (600 1450);
FORCEPROP 1 LAST PACK_TYPE 0402LF
J 0
(700 1450);
DISPLAY 0.638298 (700 1450);
FORCEPROP 1 LAST $LOCATION R4180
J 0
(150 1450);
DISPLAY 0.638298 (150 1450);
FORCEPROP 1 LASTPIN (250 1450) $PN 1
J 0
(262 1462);
DISPLAY 0.787234 (262 1462);
PAINT MONO (262 1462);
FORCEPROP 1 LASTPIN (450 1450) $PN 2
J 0
(412 1462);
DISPLAY 0.787234 (412 1462);
PAINT MONO (412 1462);
FORCEPROP 1 LAST PATH I77
J 0
(300 1600);
DISPLAY 0.978723 (300 1600);
PAINT WHITE (300 1600);
DISPLAY INVISIBLE (300 1600);
FORCEPROP 2 LAST CDS_LIB pure_quanta
J 0
(350 1450);
DISPLAY INVISIBLE (350 1450);
FORCEPROP 0 LAST CDS_LOCATION R4180
J 0
(700 1500);
DISPLAY 1.021277 (700 1500);
DISPLAY INVISIBLE (700 1500);
FORCEPROP 0 LAST $SEC 1
J 0
(700 1500);
DISPLAY 0.680851 (700 1500);
PAINT MONO (700 1500);
DISPLAY INVISIBLE (700 1500);
FORCEPROP 0 LAST CDS_SEC 1
J 0
(700 1500);
DISPLAY 1.021277 (700 1500);
DISPLAY INVISIBLE (700 1500);
FORCEADD Q_RES..1
(350 1600);
FORCEPROP 1 LAST PART_NUMBER CS03322FB03
J 0
(225 1700);
DISPLAY 0.638298 (225 1700);
DISPLAY INVISIBLE (225 1700);
FORCEPROP 1 LAST VALUE 33.2
J 2
(575 1600);
DISPLAY 0.638298 (575 1600);
FORCEPROP 1 LAST TOLERANCE 1%
J 0
(600 1600);
DISPLAY 0.638298 (600 1600);
FORCEPROP 1 LAST MATERIAL CHIP
J 0
(25 1600);
DISPLAY 0.638298 (25 1600);
FORCEPROP 1 LAST PACK_TYPE 0402LF
J 0
(700 1600);
DISPLAY 0.638298 (700 1600);
FORCEPROP 1 LAST WATTAGE 1/16W
J 2
(0 1600);
DISPLAY 0.638298 (0 1600);
FORCEPROP 1 LAST $LOCATION R4183
J 0
(150 1600);
DISPLAY 0.638298 (150 1600);
FORCEPROP 1 LASTPIN (250 1600) $PN 1
J 0
(262 1612);
DISPLAY 0.787234 (262 1612);
PAINT MONO (262 1612);
FORCEPROP 1 LASTPIN (450 1600) $PN 2
J 0
(412 1612);
DISPLAY 0.787234 (412 1612);
PAINT MONO (412 1612);
FORCEPROP 1 LAST PATH I78
J 0
(300 1750);
DISPLAY 0.978723 (300 1750);
PAINT WHITE (300 1750);
DISPLAY INVISIBLE (300 1750);
FORCEPROP 2 LAST CDS_LIB pure_quanta
J 0
(350 1600);
DISPLAY INVISIBLE (350 1600);
FORCEPROP 0 LAST CDS_LOCATION R4183
J 0
(700 1650);
DISPLAY 1.021277 (700 1650);
DISPLAY INVISIBLE (700 1650);
FORCEPROP 0 LAST $SEC 1
J 0
(700 1650);
DISPLAY 0.680851 (700 1650);
PAINT MONO (700 1650);
DISPLAY INVISIBLE (700 1650);
FORCEPROP 0 LAST CDS_SEC 1
J 0
(700 1650);
DISPLAY 1.021277 (700 1650);
DISPLAY INVISIBLE (700 1650);
FORCEADD Q_RES..1
(350 1300);
FORCEPROP 1 LAST PART_NUMBER CS00002JB13
J 0
(75 1175);
DISPLAY 0.723404 (75 1175);
PAINT WHITE (75 1175);
DISPLAY INVISIBLE (75 1175);
FORCEPROP 1 LAST MATERIAL CHIP
J 0
(525 1300);
DISPLAY 0.574468 (525 1300);
FORCEPROP 1 LAST PACK_TYPE 0402LF
J 0
(650 1300);
DISPLAY 0.574468 (650 1300);
FORCEPROP 1 LAST VALUE 0
J 2
(500 1300);
DISPLAY 0.574468 (500 1300);
FORCEPROP 1 LAST $LOCATION R4215
J 0
(150 1300);
DISPLAY 0.638298 (150 1300);
FORCEPROP 1 LASTPIN (250 1300) $PN 1
J 0
(262 1312);
DISPLAY 0.787234 (262 1312);
PAINT MONO (262 1312);
FORCEPROP 1 LASTPIN (450 1300) $PN 2
J 0
(412 1312);
DISPLAY 0.787234 (412 1312);
PAINT MONO (412 1312);
FORCEPROP 1 LAST TOLERANCE 5%
J 0
(150 1225);
DISPLAY 0.723404 (150 1225);
PAINT SKYBLUE (150 1225);
DISPLAY INVISIBLE (150 1225);
FORCEPROP 1 LAST WATTAGE 1/16W
J 2
(425 1225);
DISPLAY 0.723404 (425 1225);
PAINT SKYBLUE (425 1225);
DISPLAY INVISIBLE (425 1225);
FORCEPROP 2 LAST CDS_LIB pure_quanta
J 0
(350 1300);
DISPLAY INVISIBLE (350 1300);
FORCEPROP 1 LAST PATH I79
J 0
(300 1450);
DISPLAY 0.978723 (300 1450);
PAINT WHITE (300 1450);
DISPLAY INVISIBLE (300 1450);
FORCEPROP 0 LAST CDS_LOCATION R4215
J 0
(650 1350);
DISPLAY 1.021277 (650 1350);
DISPLAY INVISIBLE (650 1350);
FORCEPROP 0 LAST $SEC 1
J 0
(650 1350);
DISPLAY 0.680851 (650 1350);
PAINT MONO (650 1350);
DISPLAY INVISIBLE (650 1350);
FORCEPROP 0 LAST CDS_SEC 1
J 0
(650 1350);
DISPLAY 1.021277 (650 1350);
DISPLAY INVISIBLE (650 1350);
FORCEADD UNIVERSAL_GND..1
(4200 775);
FORCEPROP 3 LASTPIN (4200 825) SIG_NAME GND\g
J 0
(4210 835);
DISPLAY 0.659574 (4210 835);
PAINT MONO (4210 835);
DISPLAY INVISIBLE (4210 835);
FORCEPROP 2 LAST CDS_LIB logical_power
J 0
(4200 775);
PAINT MONO (4200 775);
DISPLAY INVISIBLE (4200 775);
FORCEPROP 1 LAST HDL_POWER GND
J 1
(4225 700);
DISPLAY 0.872340 (4225 700);
PAINT GREEN (4225 700);
DISPLAY INVISIBLE (4225 700);
FORCEPROP 1 LAST PATH I80
J 0
(4275 775);
DISPLAY 0.872340 (4275 775);
PAINT AQUA (4275 775);
DISPLAY INVISIBLE (4275 775);
FORCEADD Q_RES..2
(4200 1000);
FORCEPROP 1 LAST PART_NUMBER CS21002FB06
J 0
(4240 825);
DISPLAY 0.638298 (4240 825);
DISPLAY INVISIBLE (4240 825);
FORCEPROP 1 LAST MATERIAL CHIP
J 0
(4240 925);
DISPLAY 0.638298 (4240 925);
FORCEPROP 1 LAST PACK_TYPE 0402LF
J 0
(4240 875);
DISPLAY 0.638298 (4240 875);
FORCEPROP 1 LAST VALUE 1K
J 0
(4245 1075);
DISPLAY 0.638298 (4245 1075);
FORCEPROP 1 LAST WATTAGE 1/16W
J 0
(4240 975);
DISPLAY 0.638298 (4240 975);
FORCEPROP 1 LAST TOLERANCE 1%
J 0
(4245 1025);
DISPLAY 0.638298 (4245 1025);
FORCEPROP 1 LAST $LOCATION R4199
J 0
(4245 1125);
DISPLAY 0.638298 (4245 1125);
FORCEPROP 1 LASTPIN (4200 1100) $PN 1
J 0
(4205 1062);
DISPLAY 0.787234 (4205 1062);
PAINT MONO (4205 1062);
FORCEPROP 1 LASTPIN (4200 900) $PN 2
J 0
(4205 910);
DISPLAY 0.787234 (4205 910);
PAINT MONO (4205 910);
FORCEPROP 2 LAST CDS_LIB pure_quanta
J 0
(4200 1000);
DISPLAY INVISIBLE (4200 1000);
FORCEPROP 1 LAST PATH I81
J 0
(4250 1175);
DISPLAY 0.978723 (4250 1175);
PAINT WHITE (4250 1175);
DISPLAY INVISIBLE (4250 1175);
FORCEPROP 0 LAST CDS_LOCATION R4199
J 0
(4250 1175);
DISPLAY 1.021277 (4250 1175);
DISPLAY INVISIBLE (4250 1175);
FORCEPROP 0 LAST $SEC 1
J 0
(4250 1175);
DISPLAY 0.680851 (4250 1175);
PAINT MONO (4250 1175);
DISPLAY INVISIBLE (4250 1175);
FORCEPROP 0 LAST CDS_SEC 1
J 0
(4250 1175);
DISPLAY 1.021277 (4250 1175);
DISPLAY INVISIBLE (4250 1175);
FORCEADD Q_RES..2
(4200 1600);
FORCEPROP 1 LAST PART_NUMBER CS21002FB06
J 0
(4240 1425);
DISPLAY 0.638298 (4240 1425);
DISPLAY INVISIBLE (4240 1425);
FORCEPROP 1 LAST TOLERANCE 1%
J 0
(4245 1625);
DISPLAY 0.638298 (4245 1625);
FORCEPROP 1 LAST WATTAGE 1/16W
J 0
(4240 1575);
DISPLAY 0.638298 (4240 1575);
FORCEPROP 1 LAST VALUE 1K
J 0
(4245 1675);
DISPLAY 0.638298 (4245 1675);
FORCEPROP 1 LAST MATERIAL EMPTY
J 0
(4240 1525);
DISPLAY 0.638298 (4240 1525);
PAINT RED (4240 1525);
FORCEPROP 1 LAST PACK_TYPE 0402LF
J 0
(4240 1475);
DISPLAY 0.638298 (4240 1475);
FORCEPROP 1 LAST $LOCATION R4198
J 0
(4245 1725);
DISPLAY 0.638298 (4245 1725);
FORCEPROP 1 LASTPIN (4200 1700) $PN 1
J 0
(4205 1662);
DISPLAY 0.787234 (4205 1662);
PAINT MONO (4205 1662);
FORCEPROP 1 LASTPIN (4200 1500) $PN 2
J 0
(4205 1510);
DISPLAY 0.787234 (4205 1510);
PAINT MONO (4205 1510);
FORCEPROP 2 LAST CDS_LIB pure_quanta
J 0
(4200 1600);
DISPLAY INVISIBLE (4200 1600);
FORCEPROP 1 LAST PATH I82
J 0
(4250 1775);
DISPLAY 0.978723 (4250 1775);
PAINT WHITE (4250 1775);
DISPLAY INVISIBLE (4250 1775);
FORCEPROP 0 LAST CDS_LOCATION R4198
J 0
(4250 1775);
DISPLAY 1.021277 (4250 1775);
DISPLAY INVISIBLE (4250 1775);
FORCEPROP 0 LAST $SEC 1
J 0
(4250 1775);
DISPLAY 0.680851 (4250 1775);
PAINT MONO (4250 1775);
DISPLAY INVISIBLE (4250 1775);
FORCEPROP 0 LAST CDS_SEC 1
J 0
(4250 1775);
DISPLAY 1.021277 (4250 1775);
DISPLAY INVISIBLE (4250 1775);
FORCEADD UNIVERSAL_POWER..1
(4450 2025);
FORCEPROP 3 LASTPIN (4450 1975) SIG_NAME P3V3_AUX\g
J 0
(4460 1985);
DISPLAY 0.659574 (4460 1985);
PAINT MONO (4460 1985);
DISPLAY INVISIBLE (4460 1985);
FORCEPROP 1 LAST HDL_POWER P3V3_AUX
J 1
(4450 2075);
DISPLAY 0.872340 (4450 2075);
PAINT GREEN (4450 2075);
FORCEPROP 2 LAST CDS_LIB logical_power
J 0
(4450 2025);
PAINT MONO (4450 2025);
DISPLAY INVISIBLE (4450 2025);
FORCEPROP 1 LAST PATH I83
J 0
(4500 2050);
DISPLAY 0.872340 (4500 2050);
PAINT AQUA (4500 2050);
DISPLAY INVISIBLE (4500 2050);
FORCEADD UNIVERSAL_GND..1
(4450 775);
FORCEPROP 3 LASTPIN (4450 825) SIG_NAME GND\g
J 0
(4460 835);
DISPLAY 0.659574 (4460 835);
PAINT MONO (4460 835);
DISPLAY INVISIBLE (4460 835);
FORCEPROP 2 LAST CDS_LIB logical_power
J 0
(4450 775);
PAINT MONO (4450 775);
DISPLAY INVISIBLE (4450 775);
FORCEPROP 1 LAST HDL_POWER GND
J 1
(4475 700);
DISPLAY 0.872340 (4475 700);
PAINT GREEN (4475 700);
DISPLAY INVISIBLE (4475 700);
FORCEPROP 1 LAST PATH I84
J 0
(4525 775);
DISPLAY 0.872340 (4525 775);
PAINT AQUA (4525 775);
DISPLAY INVISIBLE (4525 775);
FORCEADD Q_RES..2
(4450 1000);
FORCEPROP 1 LAST PART_NUMBER CS21002FB06
J 0
(4490 825);
DISPLAY 0.638298 (4490 825);
DISPLAY INVISIBLE (4490 825);
FORCEPROP 1 LAST MATERIAL CHIP
J 0
(4490 925);
DISPLAY 0.638298 (4490 925);
FORCEPROP 1 LAST PACK_TYPE 0402LF
J 0
(4490 875);
DISPLAY 0.638298 (4490 875);
FORCEPROP 1 LAST WATTAGE 1/16W
J 0
(4490 975);
DISPLAY 0.638298 (4490 975);
FORCEPROP 1 LAST VALUE 1K
J 0
(4495 1075);
DISPLAY 0.638298 (4495 1075);
FORCEPROP 1 LAST TOLERANCE 1%
J 0
(4495 1025);
DISPLAY 0.638298 (4495 1025);
FORCEPROP 1 LAST $LOCATION R4207
J 0
(4495 1125);
DISPLAY 0.638298 (4495 1125);
FORCEPROP 1 LASTPIN (4450 1100) $PN 1
J 0
(4455 1062);
DISPLAY 0.787234 (4455 1062);
PAINT MONO (4455 1062);
FORCEPROP 1 LASTPIN (4450 900) $PN 2
J 0
(4455 910);
DISPLAY 0.787234 (4455 910);
PAINT MONO (4455 910);
FORCEPROP 2 LAST CDS_LIB pure_quanta
J 0
(4450 1000);
DISPLAY INVISIBLE (4450 1000);
FORCEPROP 1 LAST PATH I85
J 0
(4500 1175);
DISPLAY 0.978723 (4500 1175);
PAINT WHITE (4500 1175);
DISPLAY INVISIBLE (4500 1175);
FORCEPROP 0 LAST CDS_LOCATION R4207
J 0
(4500 1175);
DISPLAY 1.021277 (4500 1175);
DISPLAY INVISIBLE (4500 1175);
FORCEPROP 0 LAST $SEC 1
J 0
(4500 1175);
DISPLAY 0.680851 (4500 1175);
PAINT MONO (4500 1175);
DISPLAY INVISIBLE (4500 1175);
FORCEPROP 0 LAST CDS_SEC 1
J 0
(4500 1175);
DISPLAY 1.021277 (4500 1175);
DISPLAY INVISIBLE (4500 1175);
FORCEADD Q_RES..2
(4450 1600);
FORCEPROP 1 LAST PART_NUMBER CS21002FB06
J 0
(4490 1425);
DISPLAY 0.638298 (4490 1425);
DISPLAY INVISIBLE (4490 1425);
FORCEPROP 1 LAST WATTAGE 1/16W
J 0
(4490 1575);
DISPLAY 0.638298 (4490 1575);
FORCEPROP 1 LAST VALUE 1K
J 0
(4495 1675);
DISPLAY 0.638298 (4495 1675);
FORCEPROP 1 LAST PACK_TYPE 0402LF
J 0
(4490 1475);
DISPLAY 0.638298 (4490 1475);
FORCEPROP 1 LAST TOLERANCE 1%
J 0
(4495 1625);
DISPLAY 0.638298 (4495 1625);
FORCEPROP 1 LAST MATERIAL EMPTY
J 0
(4490 1525);
DISPLAY 0.638298 (4490 1525);
PAINT RED (4490 1525);
FORCEPROP 1 LAST $LOCATION R4206
J 0
(4495 1725);
DISPLAY 0.638298 (4495 1725);
FORCEPROP 1 LASTPIN (4450 1700) $PN 1
J 0
(4455 1662);
DISPLAY 0.787234 (4455 1662);
PAINT MONO (4455 1662);
FORCEPROP 1 LASTPIN (4450 1500) $PN 2
J 0
(4455 1510);
DISPLAY 0.787234 (4455 1510);
PAINT MONO (4455 1510);
FORCEPROP 2 LAST CDS_LIB pure_quanta
J 0
(4450 1600);
DISPLAY INVISIBLE (4450 1600);
FORCEPROP 1 LAST PATH I86
J 0
(4500 1775);
DISPLAY 0.978723 (4500 1775);
PAINT WHITE (4500 1775);
DISPLAY INVISIBLE (4500 1775);
FORCEPROP 0 LAST CDS_LOCATION R4206
J 0
(4500 1775);
DISPLAY 1.021277 (4500 1775);
DISPLAY INVISIBLE (4500 1775);
FORCEPROP 0 LAST $SEC 1
J 0
(4500 1775);
DISPLAY 0.680851 (4500 1775);
PAINT MONO (4500 1775);
DISPLAY INVISIBLE (4500 1775);
FORCEPROP 0 LAST CDS_SEC 1
J 0
(4500 1775);
DISPLAY 1.021277 (4500 1775);
DISPLAY INVISIBLE (4500 1775);
FORCEADD Q_RES..2
(3950 1000);
FORCEPROP 1 LAST PART_NUMBER CS21002FB06
J 0
(3990 825);
DISPLAY 0.638298 (3990 825);
DISPLAY INVISIBLE (3990 825);
FORCEPROP 1 LAST MATERIAL CHIP
J 0
(3990 925);
DISPLAY 0.638298 (3990 925);
FORCEPROP 1 LAST PACK_TYPE 0402LF
J 0
(3990 875);
DISPLAY 0.638298 (3990 875);
FORCEPROP 1 LAST VALUE 1K
J 0
(3995 1075);
DISPLAY 0.638298 (3995 1075);
FORCEPROP 1 LAST WATTAGE 1/16W
J 0
(3990 975);
DISPLAY 0.638298 (3990 975);
FORCEPROP 1 LAST TOLERANCE 1%
J 0
(3995 1025);
DISPLAY 0.638298 (3995 1025);
FORCEPROP 1 LAST $LOCATION R4191
J 0
(3995 1125);
DISPLAY 0.638298 (3995 1125);
FORCEPROP 1 LASTPIN (3950 1100) $PN 1
J 0
(3955 1062);
DISPLAY 0.787234 (3955 1062);
PAINT MONO (3955 1062);
FORCEPROP 1 LASTPIN (3950 900) $PN 2
J 0
(3955 910);
DISPLAY 0.787234 (3955 910);
PAINT MONO (3955 910);
FORCEPROP 2 LAST CDS_LIB pure_quanta
J 0
(3950 1000);
DISPLAY INVISIBLE (3950 1000);
FORCEPROP 1 LAST PATH I89
J 0
(4000 1175);
DISPLAY 0.978723 (4000 1175);
PAINT WHITE (4000 1175);
DISPLAY INVISIBLE (4000 1175);
FORCEPROP 0 LAST CDS_LOCATION R4191
J 0
(4000 1175);
DISPLAY 1.021277 (4000 1175);
DISPLAY INVISIBLE (4000 1175);
FORCEPROP 0 LAST $SEC 1
J 0
(4000 1175);
DISPLAY 0.680851 (4000 1175);
PAINT MONO (4000 1175);
DISPLAY INVISIBLE (4000 1175);
FORCEPROP 0 LAST CDS_SEC 1
J 0
(4000 1175);
DISPLAY 1.021277 (4000 1175);
DISPLAY INVISIBLE (4000 1175);
FORCEADD UNIVERSAL_GND..1
(3950 775);
FORCEPROP 3 LASTPIN (3950 825) SIG_NAME GND\g
J 0
(3960 835);
DISPLAY 0.659574 (3960 835);
PAINT MONO (3960 835);
DISPLAY INVISIBLE (3960 835);
FORCEPROP 2 LAST CDS_LIB logical_power
J 0
(3950 775);
PAINT MONO (3950 775);
DISPLAY INVISIBLE (3950 775);
FORCEPROP 1 LAST HDL_POWER GND
J 1
(3975 700);
DISPLAY 0.872340 (3975 700);
PAINT GREEN (3975 700);
DISPLAY INVISIBLE (3975 700);
FORCEPROP 1 LAST PATH I90
J 0
(4025 775);
DISPLAY 0.872340 (4025 775);
PAINT AQUA (4025 775);
DISPLAY INVISIBLE (4025 775);
FORCEADD Q_RES..2
(3950 1600);
FORCEPROP 1 LAST PART_NUMBER CS21002FB06
J 0
(3990 1425);
DISPLAY 0.638298 (3990 1425);
DISPLAY INVISIBLE (3990 1425);
FORCEPROP 1 LAST TOLERANCE 1%
J 0
(3995 1625);
DISPLAY 0.638298 (3995 1625);
FORCEPROP 1 LAST WATTAGE 1/16W
J 0
(3990 1575);
DISPLAY 0.638298 (3990 1575);
FORCEPROP 1 LAST VALUE 1K
J 0
(3995 1675);
DISPLAY 0.638298 (3995 1675);
FORCEPROP 1 LAST MATERIAL EMPTY
J 0
(3990 1525);
DISPLAY 0.638298 (3990 1525);
PAINT RED (3990 1525);
FORCEPROP 1 LAST PACK_TYPE 0402LF
J 0
(3990 1475);
DISPLAY 0.638298 (3990 1475);
FORCEPROP 1 LAST $LOCATION R4190
J 0
(3995 1725);
DISPLAY 0.638298 (3995 1725);
FORCEPROP 1 LASTPIN (3950 1700) $PN 1
J 0
(3955 1662);
DISPLAY 0.787234 (3955 1662);
PAINT MONO (3955 1662);
FORCEPROP 1 LASTPIN (3950 1500) $PN 2
J 0
(3955 1510);
DISPLAY 0.787234 (3955 1510);
PAINT MONO (3955 1510);
FORCEPROP 2 LAST CDS_LIB pure_quanta
J 0
(3950 1600);
DISPLAY INVISIBLE (3950 1600);
FORCEPROP 1 LAST PATH I91
J 0
(4000 1775);
DISPLAY 0.978723 (4000 1775);
PAINT WHITE (4000 1775);
DISPLAY INVISIBLE (4000 1775);
FORCEPROP 0 LAST CDS_LOCATION R4190
J 0
(4000 1775);
DISPLAY 1.021277 (4000 1775);
DISPLAY INVISIBLE (4000 1775);
FORCEPROP 0 LAST $SEC 1
J 0
(4000 1775);
DISPLAY 0.680851 (4000 1775);
PAINT MONO (4000 1775);
DISPLAY INVISIBLE (4000 1775);
FORCEPROP 0 LAST CDS_SEC 1
J 0
(4000 1775);
DISPLAY 1.021277 (4000 1775);
DISPLAY INVISIBLE (4000 1775);
FORCEADD UNIVERSAL_POWER..1
(4400 550);
FORCEPROP 3 LASTPIN (4400 500) SIG_NAME P3V3_AUX\g
J 0
(4410 510);
DISPLAY 0.659574 (4410 510);
PAINT MONO (4410 510);
DISPLAY INVISIBLE (4410 510);
FORCEPROP 1 LAST HDL_POWER P3V3_AUX
J 1
(4400 600);
DISPLAY 0.872340 (4400 600);
PAINT GREEN (4400 600);
FORCEPROP 1 LAST PATH I93
J 0
(4450 575);
DISPLAY 0.872340 (4450 575);
PAINT AQUA (4450 575);
DISPLAY INVISIBLE (4450 575);
FORCEPROP 2 LAST CDS_LIB logical_power
J 0
(4400 550);
PAINT MONO (4400 550);
DISPLAY INVISIBLE (4400 550);
FORCEADD Q_RES..2
(4400 125);
FORCEPROP 1 LAST PART_NUMBER CS21002FB06
J 0
(4440 -50);
DISPLAY 0.638298 (4440 -50);
DISPLAY INVISIBLE (4440 -50);
FORCEPROP 1 LAST WATTAGE 1/16W
J 0
(4440 100);
DISPLAY 0.638298 (4440 100);
FORCEPROP 1 LAST VALUE 1K
J 0
(4445 200);
DISPLAY 0.638298 (4445 200);
FORCEPROP 1 LAST PACK_TYPE 0402LF
J 0
(4440 0);
DISPLAY 0.638298 (4440 0);
FORCEPROP 1 LAST TOLERANCE 1%
J 0
(4445 150);
DISPLAY 0.638298 (4445 150);
FORCEPROP 1 LAST MATERIAL EMPTY
J 0
(4440 50);
DISPLAY 0.638298 (4440 50);
PAINT RED (4440 50);
FORCEPROP 1 LAST $LOCATION R4204
J 0
(4445 250);
DISPLAY 0.638298 (4445 250);
FORCEPROP 1 LASTPIN (4400 225) $PN 1
J 0
(4405 187);
DISPLAY 0.787234 (4405 187);
PAINT MONO (4405 187);
FORCEPROP 1 LASTPIN (4400 25) $PN 2
J 0
(4405 35);
DISPLAY 0.787234 (4405 35);
PAINT MONO (4405 35);
FORCEPROP 1 LAST PATH I94
J 0
(4450 300);
DISPLAY 0.978723 (4450 300);
PAINT WHITE (4450 300);
DISPLAY INVISIBLE (4450 300);
FORCEPROP 2 LAST CDS_LIB pure_quanta
J 0
(4400 125);
DISPLAY INVISIBLE (4400 125);
FORCEPROP 0 LAST CDS_LOCATION R4204
J 0
(4450 300);
DISPLAY 1.021277 (4450 300);
DISPLAY INVISIBLE (4450 300);
FORCEPROP 0 LAST $SEC 1
J 0
(4450 300);
DISPLAY 0.680851 (4450 300);
PAINT MONO (4450 300);
DISPLAY INVISIBLE (4450 300);
FORCEPROP 0 LAST CDS_SEC 1
J 0
(4450 300);
DISPLAY 1.021277 (4450 300);
DISPLAY INVISIBLE (4450 300);
FORCEADD Q_RES..2
(4150 125);
FORCEPROP 1 LAST PART_NUMBER CS21002FB06
J 0
(4190 -50);
DISPLAY 0.638298 (4190 -50);
DISPLAY INVISIBLE (4190 -50);
FORCEPROP 1 LAST TOLERANCE 1%
J 0
(4195 150);
DISPLAY 0.638298 (4195 150);
FORCEPROP 1 LAST WATTAGE 1/16W
J 0
(4190 100);
DISPLAY 0.638298 (4190 100);
FORCEPROP 1 LAST VALUE 1K
J 0
(4195 200);
DISPLAY 0.638298 (4195 200);
FORCEPROP 1 LAST MATERIAL EMPTY
J 0
(4190 50);
DISPLAY 0.638298 (4190 50);
PAINT RED (4190 50);
FORCEPROP 1 LAST PACK_TYPE 0402LF
J 0
(4190 0);
DISPLAY 0.638298 (4190 0);
FORCEPROP 1 LAST $LOCATION R4196
J 0
(4195 250);
DISPLAY 0.638298 (4195 250);
FORCEPROP 1 LASTPIN (4150 225) $PN 1
J 0
(4155 187);
DISPLAY 0.787234 (4155 187);
PAINT MONO (4155 187);
FORCEPROP 1 LASTPIN (4150 25) $PN 2
J 0
(4155 35);
DISPLAY 0.787234 (4155 35);
PAINT MONO (4155 35);
FORCEPROP 1 LAST PATH I95
J 0
(4200 300);
DISPLAY 0.978723 (4200 300);
PAINT WHITE (4200 300);
DISPLAY INVISIBLE (4200 300);
FORCEPROP 2 LAST CDS_LIB pure_quanta
J 0
(4150 125);
DISPLAY INVISIBLE (4150 125);
FORCEPROP 0 LAST CDS_LOCATION R4196
J 0
(4200 300);
DISPLAY 1.021277 (4200 300);
DISPLAY INVISIBLE (4200 300);
FORCEPROP 0 LAST $SEC 1
J 0
(4200 300);
DISPLAY 0.680851 (4200 300);
PAINT MONO (4200 300);
DISPLAY INVISIBLE (4200 300);
FORCEPROP 0 LAST CDS_SEC 1
J 0
(4200 300);
DISPLAY 1.021277 (4200 300);
DISPLAY INVISIBLE (4200 300);
FORCEADD Q_RES..2
(4400 -475);
FORCEPROP 1 LAST PART_NUMBER CS21002FB06
J 0
(4440 -650);
DISPLAY 0.638298 (4440 -650);
DISPLAY INVISIBLE (4440 -650);
FORCEPROP 1 LAST MATERIAL CHIP
J 0
(4440 -550);
DISPLAY 0.638298 (4440 -550);
FORCEPROP 1 LAST PACK_TYPE 0402LF
J 0
(4440 -600);
DISPLAY 0.638298 (4440 -600);
FORCEPROP 1 LAST WATTAGE 1/16W
J 0
(4440 -500);
DISPLAY 0.638298 (4440 -500);
FORCEPROP 1 LAST VALUE 1K
J 0
(4445 -400);
DISPLAY 0.638298 (4445 -400);
FORCEPROP 1 LAST TOLERANCE 1%
J 0
(4445 -450);
DISPLAY 0.638298 (4445 -450);
FORCEPROP 1 LAST $LOCATION R4205
J 0
(4445 -350);
DISPLAY 0.638298 (4445 -350);
FORCEPROP 1 LASTPIN (4400 -375) $PN 1
J 0
(4405 -413);
DISPLAY 0.787234 (4405 -413);
PAINT MONO (4405 -413);
FORCEPROP 1 LASTPIN (4400 -575) $PN 2
J 0
(4405 -565);
DISPLAY 0.787234 (4405 -565);
PAINT MONO (4405 -565);
FORCEPROP 1 LAST PATH I96
J 0
(4450 -300);
DISPLAY 0.978723 (4450 -300);
PAINT WHITE (4450 -300);
DISPLAY INVISIBLE (4450 -300);
FORCEPROP 2 LAST CDS_LIB pure_quanta
J 0
(4400 -475);
DISPLAY INVISIBLE (4400 -475);
FORCEPROP 0 LAST CDS_LOCATION R4205
J 0
(4450 -300);
DISPLAY 1.021277 (4450 -300);
DISPLAY INVISIBLE (4450 -300);
FORCEPROP 0 LAST $SEC 1
J 0
(4450 -300);
DISPLAY 0.680851 (4450 -300);
PAINT MONO (4450 -300);
DISPLAY INVISIBLE (4450 -300);
FORCEPROP 0 LAST CDS_SEC 1
J 0
(4450 -300);
DISPLAY 1.021277 (4450 -300);
DISPLAY INVISIBLE (4450 -300);
FORCEADD UNIVERSAL_GND..1
(4400 -700);
FORCEPROP 3 LASTPIN (4400 -650) SIG_NAME GND\g
J 0
(4410 -640);
DISPLAY 0.659574 (4410 -640);
PAINT MONO (4410 -640);
DISPLAY INVISIBLE (4410 -640);
FORCEPROP 1 LAST PATH I97
J 0
(4475 -700);
DISPLAY 0.872340 (4475 -700);
PAINT AQUA (4475 -700);
DISPLAY INVISIBLE (4475 -700);
FORCEPROP 2 LAST CDS_LIB logical_power
J 0
(4400 -700);
PAINT MONO (4400 -700);
DISPLAY INVISIBLE (4400 -700);
FORCEPROP 1 LAST HDL_POWER GND
J 1
(4425 -775);
DISPLAY 0.872340 (4425 -775);
PAINT GREEN (4425 -775);
DISPLAY INVISIBLE (4425 -775);
FORCEADD Q_RES..2
(4150 -475);
FORCEPROP 1 LAST PART_NUMBER CS21002FB06
J 0
(4190 -650);
DISPLAY 0.638298 (4190 -650);
DISPLAY INVISIBLE (4190 -650);
FORCEPROP 1 LAST TOLERANCE 1%
J 0
(4195 -450);
DISPLAY 0.638298 (4195 -450);
FORCEPROP 1 LAST MATERIAL CHIP
J 0
(4190 -550);
DISPLAY 0.638298 (4190 -550);
FORCEPROP 1 LAST PACK_TYPE 0402LF
J 0
(4190 -600);
DISPLAY 0.638298 (4190 -600);
FORCEPROP 1 LAST VALUE 1K
J 0
(4195 -400);
DISPLAY 0.638298 (4195 -400);
FORCEPROP 1 LAST WATTAGE 1/16W
J 0
(4190 -500);
DISPLAY 0.638298 (4190 -500);
FORCEPROP 1 LAST $LOCATION R4197
J 0
(4195 -350);
DISPLAY 0.638298 (4195 -350);
FORCEPROP 1 LASTPIN (4150 -375) $PN 1
J 0
(4155 -413);
DISPLAY 0.787234 (4155 -413);
PAINT MONO (4155 -413);
FORCEPROP 1 LASTPIN (4150 -575) $PN 2
J 0
(4155 -565);
DISPLAY 0.787234 (4155 -565);
PAINT MONO (4155 -565);
FORCEPROP 1 LAST PATH I98
J 0
(4200 -300);
DISPLAY 0.978723 (4200 -300);
PAINT WHITE (4200 -300);
DISPLAY INVISIBLE (4200 -300);
FORCEPROP 2 LAST CDS_LIB pure_quanta
J 0
(4150 -475);
DISPLAY INVISIBLE (4150 -475);
FORCEPROP 0 LAST CDS_LOCATION R4197
J 0
(4200 -300);
DISPLAY 1.021277 (4200 -300);
DISPLAY INVISIBLE (4200 -300);
FORCEPROP 0 LAST $SEC 1
J 0
(4200 -300);
DISPLAY 0.680851 (4200 -300);
PAINT MONO (4200 -300);
DISPLAY INVISIBLE (4200 -300);
FORCEPROP 0 LAST CDS_SEC 1
J 0
(4200 -300);
DISPLAY 1.021277 (4200 -300);
DISPLAY INVISIBLE (4200 -300);
FORCEADD UNIVERSAL_GND..1
(4150 -700);
FORCEPROP 3 LASTPIN (4150 -650) SIG_NAME GND\g
J 0
(4160 -640);
DISPLAY 0.659574 (4160 -640);
PAINT MONO (4160 -640);
DISPLAY INVISIBLE (4160 -640);
FORCEPROP 1 LAST PATH I99
J 0
(4225 -700);
DISPLAY 0.872340 (4225 -700);
PAINT AQUA (4225 -700);
DISPLAY INVISIBLE (4225 -700);
FORCEPROP 2 LAST CDS_LIB logical_power
J 0
(4150 -700);
PAINT MONO (4150 -700);
DISPLAY INVISIBLE (4150 -700);
FORCEPROP 1 LAST HDL_POWER GND
J 1
(4175 -775);
DISPLAY 0.872340 (4175 -775);
PAINT GREEN (4175 -775);
DISPLAY INVISIBLE (4175 -775);
FORCEADD QUANTA_TITLE_BLOCK_C..1
(6625 -4100);
FORCEPROP 0 LAST CDS_CON_LAST_MODIFIED Fri Aug 25 14:02:40 2023
J 0
(4740 -4085);
DISPLAY INVISIBLE (4740 -4085);
FORCEPROP 1 LAST CUSTOM_TXT_CDS <CON_LAST_MODIFIED>
J 0
(4740 -4085);
DISPLAY 0.978723 (4740 -4085);
FORCEPROP 2 LAST CUSTOM_TXT_CDS <XR_PAGE_TITLE>
J 0
(-1265 1150);
DISPLAY 0.638298 (-1265 1150);
PAINT PINK (-1265 1150);
DISPLAY INVISIBLE (-1265 1150);
FORCEPROP 1 LAST CUSTOM_TXT_CDS <NAME_2>
J 0
(3450 -4050);
FORCEPROP 1 LAST CUSTOM_TXT_CDS <NAME_1>
J 0
(3450 -3925);
FORCEPROP 1 LAST CUSTOM_TXT_CDS <Q_NUMBER>
J 0
(5222 -3997);
DISPLAY 1.212766 (5222 -3997);
FORCEPROP 1 LAST CUSTOM_TXT_CDS <Q_PROJ>
J 0
(4243 -3998);
DISPLAY 1.212766 (4243 -3998);
FORCEPROP 1 LAST CUSTOM_TXT_CDS <Q_REV>
J 0
(6441 -3997);
DISPLAY 1.212766 (6441 -3997);
FORCEPROP 1 LAST CUSTOM_TXT_CDS <CON_PAGE_NUM> OF <CON_TOTAL_PAGES>
J 0
(6179 -4082);
DISPLAY 0.978723 (6179 -4082);
FORCEPROP 1 LAST Q_TITLE TEMP SENSOR - LM75
J 0
(-2675 -4050);
DISPLAY 2.446809 (-2675 -4050);
PAINT GREEN (-2675 -4050);
FORCEPROP 1 LAST Q_DEPT 
J 1
(2862 -4051);
DISPLAY 1.957447 (2862 -4051);
PAINT GREEN (2862 -4051);
FORCEPROP 2 LAST CDS_XR_PAGE_TITLE CR-170 : @S9S_MB_2U_LIB.S9S_MB_2U(SCH_1):PAGE170
J 0
(-1265 1150);
DISPLAY 0.638298 (-1265 1150);
PAINT PINK (-1265 1150);
DISPLAY INVISIBLE (-1265 1150);
FORCEPROP 2 LAST CDS_LIB pure_quanta
J 0
(6625 -4100);
DISPLAY INVISIBLE (6625 -4100);
FORCEPROP 1 LAST CDS_LMAN_SYM_OUTLINE -9475,6775,100,-125
J 0
(6625 -4100);
DISPLAY 0.468085 (6625 -4100);
PAINT GREEN (6625 -4100);
DISPLAY INVISIBLE (6625 -4100);
FORCEPROP 1 LAST COMMENT_BODY TRUE
J 0
(6637 -4113);
DISPLAY 0.978723 (6637 -4113);
PAINT GREEN (6637 -4113);
DISPLAY INVISIBLE (6637 -4113);
FORCEPROP 2 LAST PAGE_BORDER TRUE
J 0
(-1265 1150);
DISPLAY 0.638298 (-1265 1150);
PAINT PINK (-1265 1150);
DISPLAY INVISIBLE (-1265 1150);
FORCEADD DNS..2
(-250 -1200);
PAINT RED (-250 -1200);
FORCEPROP 1 LAST COMMENT_BODY TRUE
J 0
(-250 -1200);
DISPLAY INVISIBLE (-250 -1200);
FORCEPROP 2 LAST CDS_LIB mstr_misc
J 0
(-250 -1200);
DISPLAY INVISIBLE (-250 -1200);
FORCEADD DNS..2
(-250 300);
PAINT RED (-250 300);
FORCEPROP 2 LAST CDS_LIB mstr_misc
J 0
(-250 300);
DISPLAY INVISIBLE (-250 300);
FORCEPROP 1 LAST COMMENT_BODY TRUE
J 0
(-250 300);
DISPLAY INVISIBLE (-250 300);
FORCEADD DNS..2
(4455 1595);
PAINT RED (4455 1595);
FORCEPROP 1 LAST COMMENT_BODY TRUE
J 0
(4455 1595);
DISPLAY INVISIBLE (4455 1595);
FORCEPROP 2 LAST CDS_LIB mstr_misc
J 0
(4455 1595);
PAINT MONO (4455 1595);
DISPLAY INVISIBLE (4455 1595);
FORCEADD DNS..2
(4200 1575);
PAINT RED (4200 1575);
FORCEPROP 2 LAST CDS_LIB mstr_misc
J 0
(4200 1575);
PAINT MONO (4200 1575);
DISPLAY INVISIBLE (4200 1575);
FORCEPROP 1 LAST COMMENT_BODY TRUE
J 0
(4200 1575);
DISPLAY INVISIBLE (4200 1575);
FORCEADD DNS..2
(3950 1575);
PAINT RED (3950 1575);
FORCEPROP 2 LAST CDS_LIB mstr_misc
J 0
(3950 1575);
PAINT MONO (3950 1575);
DISPLAY INVISIBLE (3950 1575);
FORCEPROP 1 LAST COMMENT_BODY TRUE
J 0
(3950 1575);
DISPLAY INVISIBLE (3950 1575);
FORCEADD DNS..2
(4405 120);
PAINT RED (4405 120);
FORCEPROP 1 LAST COMMENT_BODY TRUE
J 0
(4405 120);
DISPLAY INVISIBLE (4405 120);
FORCEPROP 2 LAST CDS_LIB mstr_misc
J 0
(4405 120);
PAINT MONO (4405 120);
DISPLAY INVISIBLE (4405 120);
FORCEADD DNS..2
(4150 100);
PAINT RED (4150 100);
FORCEPROP 2 LAST CDS_LIB mstr_misc
J 0
(4150 100);
PAINT MONO (4150 100);
DISPLAY INVISIBLE (4150 100);
FORCEPROP 1 LAST COMMENT_BODY TRUE
J 0
(4150 100);
DISPLAY INVISIBLE (4150 100);
FORCEADD DNS..2
(4380 -1355);
PAINT RED (4380 -1355);
FORCEPROP 2 LAST CDS_LIB mstr_misc
J 0
(4380 -1355);
PAINT MONO (4380 -1355);
DISPLAY INVISIBLE (4380 -1355);
FORCEPROP 1 LAST COMMENT_BODY TRUE
J 0
(4380 -1355);
DISPLAY INVISIBLE (4380 -1355);
FORCEADD DNS..2
(4125 -1375);
PAINT RED (4125 -1375);
FORCEPROP 1 LAST COMMENT_BODY TRUE
J 0
(4125 -1375);
DISPLAY INVISIBLE (4125 -1375);
FORCEPROP 2 LAST CDS_LIB mstr_misc
J 0
(4125 -1375);
PAINT MONO (4125 -1375);
DISPLAY INVISIBLE (4125 -1375);
FORCEADD DNS..2
(3875 -1375);
PAINT RED (3875 -1375);
FORCEPROP 1 LAST COMMENT_BODY TRUE
J 0
(3875 -1375);
DISPLAY INVISIBLE (3875 -1375);
FORCEPROP 2 LAST CDS_LIB mstr_misc
J 0
(3875 -1375);
PAINT MONO (3875 -1375);
DISPLAY INVISIBLE (3875 -1375);
FORCEADD DNS..2
(4330 -2830);
PAINT RED (4330 -2830);
FORCEPROP 1 LAST COMMENT_BODY TRUE
J 0
(4330 -2830);
DISPLAY INVISIBLE (4330 -2830);
FORCEPROP 2 LAST CDS_LIB mstr_misc
J 0
(4330 -2830);
PAINT MONO (4330 -2830);
DISPLAY INVISIBLE (4330 -2830);
FORCEADD DNS..2
(4075 -2850);
PAINT RED (4075 -2850);
FORCEPROP 2 LAST CDS_LIB mstr_misc
J 0
(4075 -2850);
PAINT MONO (4075 -2850);
DISPLAY INVISIBLE (4075 -2850);
FORCEPROP 1 LAST COMMENT_BODY TRUE
J 0
(4075 -2850);
DISPLAY INVISIBLE (4075 -2850);
FORCEADD DNS..2
(3825 -2850);
PAINT RED (3825 -2850);
FORCEPROP 2 LAST CDS_LIB mstr_misc
J 0
(3825 -2850);
PAINT MONO (3825 -2850);
DISPLAY INVISIBLE (3825 -2850);
FORCEPROP 1 LAST COMMENT_BODY TRUE
J 0
(3825 -2850);
DISPLAY INVISIBLE (3825 -2850);
FORCEADD DNS..2
(3900 100);
PAINT RED (3900 100);
FORCEPROP 1 LAST COMMENT_BODY TRUE
J 0
(3900 100);
DISPLAY INVISIBLE (3900 100);
FORCEPROP 2 LAST CDS_LIB mstr_misc
J 0
(3900 100);
PAINT MONO (3900 100);
DISPLAY INVISIBLE (3900 100);
FORCEADD DNS..2
(-350 -2650);
PAINT RED (-350 -2650);
FORCEPROP 2 LAST CDS_LIB mstr_misc
J 0
(-350 -2650);
DISPLAY INVISIBLE (-350 -2650);
FORCEPROP 1 LAST COMMENT_BODY TRUE
J 0
(-350 -2650);
DISPLAY INVISIBLE (-350 -2650);
WIRE 16 -1 (-350 -2525)(-350 -2400);
WIRE 16 -1 (-250 425)(-250 500);
WIRE 16 -1 (-200 1900)(-200 1975);
WIRE 16 -1 (4325 -2450)(4325 -2550);
WIRE 16 -1 (2475 -2300)(2475 -2200);
WIRE 16 -1 (2475 -2300)(2800 -2300);
WIRE 16 -1 (2475 -2375)(2475 -2300);
WIRE 16 -1 (-250 -1075)(-250 -975);
WIRE 16 -1 (2525 -825)(2525 -725);
WIRE 16 -1 (2525 -825)(2850 -825);
WIRE 16 -1 (2525 -900)(2525 -825);
WIRE 16 -1 (2550 650)(2550 750);
WIRE 16 -1 (2550 650)(2875 650);
WIRE 16 -1 (2550 575)(2550 650);
WIRE 16 -1 (4450 1975)(4450 1875);
WIRE 16 -1 (4400 500)(4400 400);
WIRE 16 -1 (4375 -975)(4375 -1075);
WIRE 16 -1 (2600 2125)(2600 2225);
WIRE 16 -1 (2600 2125)(2925 2125);
WIRE 16 -1 (2600 2050)(2600 2125);
WIRE 16 -1 (1550 -3275)(1550 -3350);
WIRE 16 -1 (1650 -3275)(1550 -3275);
WIRE 16 -1 (1600 -1800)(1600 -1875);
WIRE 16 -1 (1700 -1800)(1600 -1800);
WIRE 16 -1 (1625 -325)(1625 -400);
WIRE 16 -1 (1725 -325)(1625 -325);
WIRE 16 -1 (1675 1150)(1675 1075);
WIRE 16 -1 (1775 1150)(1675 1150);
WIRE 16 -1 (4450 900)(4450 825);
WIRE 16 -1 (4200 900)(4200 825);
WIRE 16 -1 (3950 900)(3950 825);
WIRE 16 -1 (2600 1850)(2600 1775);
WIRE 16 -1 (4400 -575)(4400 -650);
WIRE 16 -1 (4150 -575)(4150 -650);
WIRE 16 -1 (3900 -575)(3900 -650);
WIRE 16 -1 (2550 375)(2550 300);
WIRE 16 -1 (4375 -2050)(4375 -2125);
WIRE 16 -1 (4125 -2050)(4125 -2125);
WIRE 16 -1 (3875 -2050)(3875 -2125);
WIRE 16 -1 (2525 -1100)(2525 -1175);
WIRE 16 -1 (4325 -3525)(4325 -3600);
WIRE 16 -1 (4075 -3525)(4075 -3600);
WIRE 16 -1 (3825 -3525)(3825 -3600);
WIRE 16 -1 (2475 -2575)(2475 -2650);
WIRE 16 -1 (-350 -2725)(-350 -3125);
WIRE 16 -1 (-350 -3125)(125 -3125);
WIRE 16 -1 (-1000 -3125)(-350 -3125);
FORCEPROP 2 LAST SIG_NAME FM_THERMAL_ALERT_N
J 0
(-985 -3115);
DISPLAY 0.638298 (-985 -3115);
PAINT WHITE (-985 -3115);
WIRE 16 -1 (-250 -1275)(-250 -1650);
WIRE 16 -1 (-250 -1650)(175 -1650);
WIRE 16 -1 (-925 -1650)(-250 -1650);
FORCEPROP 2 LAST SIG_NAME FM_THERMAL_ALERT_N
J 0
(-935 -1640);
DISPLAY 0.638298 (-935 -1640);
PAINT WHITE (-935 -1640);
WIRE 16 -1 (-250 225)(-250 -175);
WIRE 16 -1 (-250 -175)(200 -175);
WIRE 16 -1 (-925 -175)(-250 -175);
FORCEPROP 2 LAST SIG_NAME FM_THERMAL_ALERT_N
J 0
(-910 -165);
DISPLAY 0.638298 (-910 -165);
PAINT WHITE (-910 -165);
WIRE 16 -1 (-850 1600)(250 1600);
FORCEPROP 2 LAST SIG_NAME SMB_LM75_0_3V3AUX_SDA
J 0
(-860 1610);
DISPLAY 0.638298 (-860 1610);
PAINT WHITE (-860 1610);
WIRE 16 -1 (-200 1700)(-200 1300);
WIRE 16 -1 (-200 1300)(250 1300);
WIRE 16 -1 (-850 1300)(-200 1300);
FORCEPROP 2 LAST SIG_NAME FM_THERMAL_ALERT_N
J 0
(-860 1310);
DISPLAY 0.638298 (-860 1310);
PAINT WHITE (-860 1310);
WIRE 16 -1 (450 1600)(1775 1600);
FORCEPROP 2 LAST SIG_NAME SMB_LM75_0_3V3AUX_SDA_R1
J 0
(940 1610);
DISPLAY 0.638298 (940 1610);
PAINT WHITE (940 1610);
WIRE 16 -1 (450 1300)(1775 1300);
FORCEPROP 2 LAST SIG_NAME FM_G751_0_ALERT_N
J 0
(940 1310);
DISPLAY 0.638298 (940 1310);
PAINT WHITE (940 1310);
WIRE 16 -1 (450 1450)(1775 1450);
FORCEPROP 2 LAST SIG_NAME SMB_LM75_0_3V3AUX_SCL_R1
J 0
(940 1460);
DISPLAY 0.638298 (940 1460);
PAINT WHITE (940 1460);
WIRE 16 -1 (-900 125)(200 125);
FORCEPROP 2 LAST SIG_NAME SMB_LM75_1_3V3AUX_SDA
J 0
(-910 135);
DISPLAY 0.638298 (-910 135);
PAINT WHITE (-910 135);
WIRE 16 -1 (2475 -25)(4400 -25);
FORCEPROP 0 LAST CDS_PHYS_NET_NAME TCA9539_0_ADD0
J 0
(2915 17);
PAINT MONO (2915 17);
DISPLAY INVISIBLE (2915 17);
FORCEPROP 2 LAST SIG_NAME U271_1_ADD0
J 0
(2690 -15);
DISPLAY 0.553191 (2690 -15);
PAINT WHITE (2690 -15);
WIRE 16 -1 (4400 -25)(4400 25);
WIRE 16 -1 (4400 -375)(4400 -25);
WIRE 16 -1 (2875 125)(2475 125);
WIRE 16 -1 (2875 650)(2875 125);
WIRE 16 -1 (400 -25)(1725 -25);
FORCEPROP 2 LAST SIG_NAME SMB_LM75_1_3V3AUX_SCL_R1
J 0
(890 -15);
DISPLAY 0.638298 (890 -15);
PAINT WHITE (890 -15);
WIRE 16 -1 (400 125)(1725 125);
FORCEPROP 2 LAST SIG_NAME SMB_LM75_1_3V3AUX_SDA_R1
J 0
(890 135);
DISPLAY 0.638298 (890 135);
PAINT WHITE (890 135);
WIRE 16 -1 (375 -1650)(1700 -1650);
FORCEPROP 2 LAST SIG_NAME FM_LM75_2_ALERT_N
J 0
(865 -1640);
DISPLAY 0.638298 (865 -1640);
PAINT WHITE (865 -1640);
WIRE 16 -1 (375 -1350)(1700 -1350);
FORCEPROP 2 LAST SIG_NAME SMB_LM75_2_3V3AUX_SDA_R1
J 0
(865 -1340);
DISPLAY 0.638298 (865 -1340);
PAINT WHITE (865 -1340);
WIRE 16 -1 (400 -175)(1725 -175);
FORCEPROP 2 LAST SIG_NAME FM_G751_1_ALERT_N
J 0
(890 -165);
DISPLAY 0.638298 (890 -165);
PAINT WHITE (890 -165);
WIRE 16 -1 (-975 -2825)(125 -2825);
FORCEPROP 2 LAST SIG_NAME SMB_LM75_3_3V3AUX_SDA
J 0
(-985 -2815);
DISPLAY 0.638298 (-985 -2815);
PAINT WHITE (-985 -2815);
WIRE 16 -1 (325 -2975)(1650 -2975);
FORCEPROP 2 LAST SIG_NAME SMB_LM75_3_3V3AUX_SCL_R1
J 0
(815 -2965);
DISPLAY 0.638298 (815 -2965);
PAINT WHITE (815 -2965);
WIRE 16 -1 (325 -2825)(1650 -2825);
FORCEPROP 2 LAST SIG_NAME SMB_LM75_3_3V3AUX_SDA_R1
J 0
(815 -2815);
DISPLAY 0.638298 (815 -2815);
PAINT WHITE (815 -2815);
WIRE 16 -1 (2800 -2825)(2400 -2825);
WIRE 16 -1 (2800 -2300)(2800 -2825);
FORCEPROP 0 LAST VOLTAGE 3.3
J 0
(2800 -2538);
DISPLAY INVISIBLE (2800 -2538);
WIRE 16 -1 (4325 -3325)(4325 -2975);
WIRE 16 -1 (4325 -2975)(4325 -2925);
WIRE 16 -1 (2400 -2975)(4325 -2975);
FORCEPROP 0 LAST CDS_PHYS_NET_NAME TCA9539_0_ADD0
J 0
(2840 -2933);
PAINT MONO (2840 -2933);
DISPLAY INVISIBLE (2840 -2933);
FORCEPROP 2 LAST SIG_NAME U273_3_ADD0
J 0
(2615 -2965);
DISPLAY 0.553191 (2615 -2965);
PAINT WHITE (2615 -2965);
WIRE 16 -1 (4075 -3325)(4075 -3125);
WIRE 16 -1 (4075 -3125)(4075 -2925);
WIRE 16 -1 (2400 -3125)(4075 -3125);
FORCEPROP 0 LAST CDS_PHYS_NET_NAME TCA9539_0_ADD1
J 0
(3090 -3083);
PAINT MONO (3090 -3083);
DISPLAY INVISIBLE (3090 -3083);
FORCEPROP 2 LAST SIG_NAME U273_3_ADD1
J 0
(2615 -3115);
DISPLAY 0.553191 (2615 -3115);
PAINT WHITE (2615 -3115);
WIRE 16 -1 (3825 -3325)(3825 -3275);
WIRE 16 -1 (3825 -3275)(3825 -2925);
WIRE 16 -1 (2400 -3275)(3825 -3275);
FORCEPROP 0 LAST CDS_PHYS_NET_NAME TCA9539_0_ADD1
J 0
(3090 -3233);
PAINT MONO (3090 -3233);
DISPLAY INVISIBLE (3090 -3233);
FORCEPROP 2 LAST SIG_NAME U273_3_ADD2
J 0
(2615 -3265);
DISPLAY 0.553191 (2615 -3265);
PAINT WHITE (2615 -3265);
WIRE 16 -1 (325 -3125)(1650 -3125);
FORCEPROP 2 LAST SIG_NAME FM_LM75_3_ALERT_N
J 0
(815 -3115);
DISPLAY 0.638298 (815 -3115);
PAINT WHITE (815 -3115);
WIRE 16 -1 (-975 -2975)(125 -2975);
FORCEPROP 2 LAST SIG_NAME SMB_LM75_3_3V3AUX_SCL
J 0
(-985 -2965);
DISPLAY 0.638298 (-985 -2965);
PAINT WHITE (-985 -2965);
WIRE 16 -1 (375 -1500)(1700 -1500);
FORCEPROP 2 LAST SIG_NAME SMB_LM75_2_3V3AUX_SCL_R1
J 0
(865 -1490);
DISPLAY 0.638298 (865 -1490);
PAINT WHITE (865 -1490);
WIRE 16 -1 (4125 -1850)(4125 -1650);
WIRE 16 -1 (4125 -1650)(4125 -1450);
WIRE 16 -1 (2450 -1650)(4125 -1650);
FORCEPROP 0 LAST CDS_PHYS_NET_NAME TCA9539_0_ADD1
J 0
(3140 -1608);
PAINT MONO (3140 -1608);
DISPLAY INVISIBLE (3140 -1608);
FORCEPROP 2 LAST SIG_NAME U272_2_ADD1
J 0
(2665 -1640);
DISPLAY 0.553191 (2665 -1640);
PAINT WHITE (2665 -1640);
WIRE 16 -1 (3875 -1850)(3875 -1800);
WIRE 16 -1 (3875 -1800)(3875 -1450);
WIRE 16 -1 (2450 -1800)(3875 -1800);
FORCEPROP 0 LAST CDS_PHYS_NET_NAME TCA9539_0_ADD1
J 0
(3140 -1758);
PAINT MONO (3140 -1758);
DISPLAY INVISIBLE (3140 -1758);
FORCEPROP 2 LAST SIG_NAME U272_2_ADD2
J 0
(2665 -1790);
DISPLAY 0.553191 (2665 -1790);
PAINT WHITE (2665 -1790);
WIRE 16 -1 (4375 -1850)(4375 -1500);
WIRE 16 -1 (4375 -1500)(4375 -1450);
WIRE 16 -1 (2450 -1500)(4375 -1500);
FORCEPROP 0 LAST CDS_PHYS_NET_NAME TCA9539_0_ADD0
J 0
(2890 -1458);
PAINT MONO (2890 -1458);
DISPLAY INVISIBLE (2890 -1458);
FORCEPROP 2 LAST SIG_NAME U272_2_ADD0
J 0
(2665 -1490);
DISPLAY 0.553191 (2665 -1490);
PAINT WHITE (2665 -1490);
WIRE 16 -1 (2850 -1350)(2450 -1350);
WIRE 16 -1 (2850 -825)(2850 -1350);
FORCEPROP 0 LAST VOLTAGE 3.3
J 0
(2850 -1063);
DISPLAY INVISIBLE (2850 -1063);
WIRE 16 -1 (-925 -1350)(175 -1350);
FORCEPROP 2 LAST SIG_NAME SMB_LM75_2_3V3AUX_SDA
J 0
(-935 -1340);
DISPLAY 0.638298 (-935 -1340);
PAINT WHITE (-935 -1340);
WIRE 16 -1 (-925 -1500)(175 -1500);
FORCEPROP 2 LAST SIG_NAME SMB_LM75_2_3V3AUX_SCL
J 0
(-935 -1490);
DISPLAY 0.638298 (-935 -1490);
PAINT WHITE (-935 -1490);
WIRE 16 -1 (3900 -375)(3900 -325);
WIRE 16 -1 (3900 -325)(3900 25);
WIRE 16 -1 (2475 -325)(3900 -325);
FORCEPROP 0 LAST CDS_PHYS_NET_NAME TCA9539_0_ADD1
J 0
(3165 -283);
PAINT MONO (3165 -283);
DISPLAY INVISIBLE (3165 -283);
FORCEPROP 2 LAST SIG_NAME U271_1_ADD2
J 0
(2690 -315);
DISPLAY 0.553191 (2690 -315);
PAINT WHITE (2690 -315);
WIRE 16 -1 (4150 -375)(4150 -175);
WIRE 16 -1 (4150 -175)(4150 25);
WIRE 16 -1 (2475 -175)(4150 -175);
FORCEPROP 0 LAST CDS_PHYS_NET_NAME TCA9539_0_ADD1
J 0
(3165 -133);
PAINT MONO (3165 -133);
DISPLAY INVISIBLE (3165 -133);
FORCEPROP 2 LAST SIG_NAME U271_1_ADD1
J 0
(2690 -165);
DISPLAY 0.553191 (2690 -165);
PAINT WHITE (2690 -165);
WIRE 16 -1 (-900 -25)(200 -25);
FORCEPROP 2 LAST SIG_NAME SMB_LM75_1_3V3AUX_SCL
J 0
(-910 -15);
DISPLAY 0.638298 (-910 -15);
PAINT WHITE (-910 -15);
WIRE 16 -1 (4200 1100)(4200 1300);
WIRE 16 -1 (4200 1300)(4200 1500);
WIRE 16 -1 (2525 1300)(4200 1300);
FORCEPROP 0 LAST CDS_PHYS_NET_NAME TCA9539_0_ADD1
J 0
(3215 1342);
PAINT MONO (3215 1342);
DISPLAY INVISIBLE (3215 1342);
FORCEPROP 2 LAST SIG_NAME U270_0_ADD1
J 0
(2740 1310);
DISPLAY 0.553191 (2740 1310);
PAINT WHITE (2740 1310);
WIRE 16 -1 (3950 1100)(3950 1150);
WIRE 16 -1 (3950 1150)(3950 1500);
WIRE 16 -1 (2525 1150)(3950 1150);
FORCEPROP 0 LAST CDS_PHYS_NET_NAME TCA9539_0_ADD1
J 0
(3215 1192);
PAINT MONO (3215 1192);
DISPLAY INVISIBLE (3215 1192);
FORCEPROP 2 LAST SIG_NAME U270_0_ADD2
J 0
(2740 1160);
DISPLAY 0.553191 (2740 1160);
PAINT WHITE (2740 1160);
WIRE 16 -1 (4450 1100)(4450 1450);
WIRE 16 -1 (4450 1450)(4450 1500);
WIRE 16 -1 (2525 1450)(4450 1450);
FORCEPROP 0 LAST CDS_PHYS_NET_NAME TCA9539_0_ADD0
J 0
(2965 1492);
PAINT MONO (2965 1492);
DISPLAY INVISIBLE (2965 1492);
FORCEPROP 2 LAST SIG_NAME U270_0_ADD0
J 0
(2740 1460);
DISPLAY 0.553191 (2740 1460);
PAINT WHITE (2740 1460);
WIRE 16 -1 (2925 1600)(2525 1600);
WIRE 16 -1 (2925 2125)(2925 1600);
WIRE 16 -1 (-850 1450)(250 1450);
FORCEPROP 2 LAST SIG_NAME SMB_LM75_0_3V3AUX_SCL
J 0
(-860 1460);
DISPLAY 0.638298 (-860 1460);
PAINT WHITE (-860 1460);
WIRE 16 -1 (4375 -1250)(4375 -1075);
WIRE 16 -1 (4125 -1250)(4125 -1075);
WIRE 16 -1 (4375 -1075)(4125 -1075);
WIRE 16 -1 (3875 -1075)(4125 -1075);
WIRE 16 -1 (3875 -1250)(3875 -1075);
WIRE 16 -1 (4325 -2725)(4325 -2550);
WIRE 16 -1 (4075 -2725)(4075 -2550);
WIRE 16 -1 (4325 -2550)(4075 -2550);
WIRE 16 -1 (3825 -2550)(4075 -2550);
WIRE 16 -1 (3825 -2725)(3825 -2550);
WIRE 16 -1 (4450 1700)(4450 1875);
WIRE 16 -1 (4200 1700)(4200 1875);
WIRE 16 -1 (4450 1875)(4200 1875);
WIRE 16 -1 (3950 1875)(4200 1875);
WIRE 16 -1 (3950 1700)(3950 1875);
WIRE 16 -1 (4400 225)(4400 400);
WIRE 16 -1 (4150 225)(4150 400);
WIRE 16 -1 (4400 400)(4150 400);
WIRE 16 -1 (3900 400)(4150 400);
WIRE 16 -1 (3900 225)(3900 400);
DOT 1 (2600 2125);
DOT 1 (4325 -2550);
DOT 1 (4075 -2550);
DOT 1 (4325 -2975);
DOT 1 (2475 -2300);
DOT 1 (2525 -825);
DOT 1 (4375 -1500);
DOT 1 (4125 -1075);
DOT 1 (4375 -1075);
DOT 1 (4400 -25);
DOT 1 (4150 400);
DOT 1 (4400 400);
DOT 1 (2550 650);
DOT 1 (4450 1875);
DOT 1 (4200 1875);
DOT 1 (4450 1450);
DOT 1 (-200 1300);
DOT 1 (3950 1150);
DOT 1 (4200 1300);
DOT 1 (-250 -175);
DOT 1 (3900 -325);
DOT 1 (4150 -175);
DOT 1 (-250 -1650);
DOT 1 (3875 -1800);
DOT 1 (4125 -1650);
DOT 1 (-350 -3125);
DOT 1 (3825 -3275);
DOT 1 (4075 -3125);
FORCENOTE
ADDRESS : 0X90
(1750 950) 0;
DISPLAY LEFT (1750 950);
DISPLAY 1.340425 (1750 950);
PAINT WHITE (1750 950);
FORCENOTE
ADDRESS : 0X90
(1625 -3475) 0;
DISPLAY LEFT (1625 -3475);
DISPLAY 1.340425 (1625 -3475);
PAINT WHITE (1625 -3475);
FORCENOTE
ADDRESS : 0X90
(1700 -2025) 0;
DISPLAY LEFT (1700 -2025);
DISPLAY 1.340425 (1700 -2025);
PAINT WHITE (1700 -2025);
FORCENOTE
ADDRESS : 0X90
(1725 -525) 0;
DISPLAY LEFT (1725 -525);
DISPLAY 1.340425 (1725 -525);
PAINT WHITE (1725 -525);
FORCENOTE
20211201 MODIFY FOR GT
(-2450 2250) 0;
DISPLAY LEFT (-2450 2250);
DISPLAY 2.510638 (-2450 2250);
PAINT PINK (-2450 2250);
QUIT
